G04*
G04 #@! TF.GenerationSoftware,Altium Limited,Altium Designer,23.6.0 (18)*
G04*
G04 Layer_Color=8388736*
%FSLAX44Y44*%
%MOMM*%
G71*
G04*
G04 #@! TF.SameCoordinates,0D6CC9A4-690D-4EF8-AA6E-9FB67146BD04*
G04*
G04*
G04 #@! TF.FilePolarity,Negative*
G04*
G01*
G75*
%ADD18R,1.5000X1.0000*%
%ADD39R,7.0000X10.5500*%
%ADD40R,2.6500X1.1500*%
%ADD41R,0.5500X0.5500*%
%ADD42R,1.3500X0.9500*%
%ADD43R,0.7500X1.3500*%
G04:AMPARAMS|DCode=44|XSize=2.4mm|YSize=1.3mm|CornerRadius=0.41mm|HoleSize=0mm|Usage=FLASHONLY|Rotation=90.000|XOffset=0mm|YOffset=0mm|HoleType=Round|Shape=RoundedRectangle|*
%AMROUNDEDRECTD44*
21,1,2.4000,0.4800,0,0,90.0*
21,1,1.5800,1.3000,0,0,90.0*
1,1,0.8200,0.2400,0.7900*
1,1,0.8200,0.2400,-0.7900*
1,1,0.8200,-0.2400,-0.7900*
1,1,0.8200,-0.2400,0.7900*
%
%ADD44ROUNDEDRECTD44*%
G04:AMPARAMS|DCode=45|XSize=2.9mm|YSize=1.3mm|CornerRadius=0.41mm|HoleSize=0mm|Usage=FLASHONLY|Rotation=90.000|XOffset=0mm|YOffset=0mm|HoleType=Round|Shape=RoundedRectangle|*
%AMROUNDEDRECTD45*
21,1,2.9000,0.4800,0,0,90.0*
21,1,2.0800,1.3000,0,0,90.0*
1,1,0.8200,0.2400,1.0400*
1,1,0.8200,0.2400,-1.0400*
1,1,0.8200,-0.2400,-1.0400*
1,1,0.8200,-0.2400,1.0400*
%
%ADD45ROUNDEDRECTD45*%
%ADD46R,2.8000X1.2500*%
%ADD47R,0.7200X0.6700*%
%ADD48R,0.5400X0.5200*%
%ADD49R,3.5000X2.8000*%
%ADD50C,1.6000*%
%ADD51R,2.3300X1.9000*%
%ADD52R,1.7500X1.4000*%
%ADD53R,1.0500X1.1000*%
%ADD54R,1.1000X1.0500*%
%ADD55R,0.7200X0.7000*%
%ADD56R,1.4000X1.7500*%
%ADD57R,0.7000X0.7200*%
%ADD58R,0.6700X0.7200*%
G04:AMPARAMS|DCode=59|XSize=0.67mm|YSize=0.72mm|CornerRadius=0mm|HoleSize=0mm|Usage=FLASHONLY|Rotation=45.000|XOffset=0mm|YOffset=0mm|HoleType=Round|Shape=Rectangle|*
%AMROTATEDRECTD59*
4,1,4,0.0177,-0.4914,-0.4914,0.0177,-0.0177,0.4914,0.4914,-0.0177,0.0177,-0.4914,0.0*
%
%ADD59ROTATEDRECTD59*%

%ADD60C,2.0000*%
%ADD61R,0.5200X0.5400*%
%ADD62R,2.1200X2.1200*%
%ADD63C,2.1200*%
%ADD64C,2.1900*%
%ADD65C,5.7000*%
%ADD66C,0.1000*%
%ADD67C,0.7000*%
G36*
X13295Y322817D02*
X13337Y322803D01*
X13725Y322789D01*
X13767Y322775D01*
X13822Y322761D01*
X13892Y322734D01*
X13947Y322720D01*
X14141Y322692D01*
X14287Y322657D01*
X14405Y322595D01*
X14474Y322567D01*
X14564Y322533D01*
X14613Y322498D01*
X14682Y322456D01*
X14751Y322429D01*
X14842Y322394D01*
X14862Y322373D01*
X14890Y322359D01*
X15043Y322290D01*
X15140Y322234D01*
X15209Y322193D01*
X15278Y322165D01*
X15334Y322151D01*
X15410Y322089D01*
X15459Y322040D01*
X15486Y322026D01*
X15549Y321964D01*
X15563Y321936D01*
X15583Y321915D01*
X15611Y321902D01*
X15688Y321825D01*
X15701Y321797D01*
X15722Y321777D01*
X15750Y321763D01*
X15826Y321687D01*
X15840Y321659D01*
X15861Y321638D01*
X15889Y321624D01*
X15951Y321562D01*
X15965Y321534D01*
X15999Y321499D01*
X16027Y321485D01*
X16076Y321437D01*
X16090Y321409D01*
X16173Y321326D01*
X16201Y321257D01*
X16235Y321166D01*
X16270Y321118D01*
X16339Y321049D01*
X16381Y320979D01*
X16450Y320910D01*
X16499Y320778D01*
X16520Y320730D01*
X16589Y320619D01*
X16603Y320522D01*
X16617Y320466D01*
X16631Y320383D01*
X16728Y320175D01*
X16748Y320043D01*
X16804Y319904D01*
X16818Y319849D01*
X16832Y319766D01*
X16846Y319461D01*
X16859Y319086D01*
X16873Y318254D01*
X16880Y284798D01*
Y284784D01*
X16873Y255585D01*
X16880Y255537D01*
X16866Y255495D01*
X16873Y255266D01*
X16866Y255051D01*
X16880Y255010D01*
X16866Y254954D01*
X16852Y254857D01*
X16866Y254802D01*
X16873Y254726D01*
X16859Y254656D01*
X16846Y254601D01*
X16832Y254240D01*
X16804Y254171D01*
X16707Y254074D01*
X16637Y254046D01*
X16249Y254032D01*
X16207Y254018D01*
X16152Y254004D01*
X16020Y254025D01*
X15986Y254032D01*
X15944Y254018D01*
X15847Y254004D01*
X15708Y254018D01*
X15570Y254004D01*
X15285Y254011D01*
X15181Y254004D01*
X15140Y254018D01*
X15063Y254025D01*
X14980Y254011D01*
X14904Y254004D01*
X14862Y254018D01*
X14751Y254046D01*
X14405Y254060D01*
X14328Y254122D01*
X14273Y254178D01*
X14245Y254247D01*
X14231Y254635D01*
X14217Y254677D01*
X14204Y254774D01*
X14217Y254816D01*
X14231Y254899D01*
X14217Y254940D01*
X14204Y255038D01*
X14217Y255093D01*
X14211Y255336D01*
X14217Y255495D01*
X14204Y255537D01*
X14211Y255724D01*
X14197Y318337D01*
X14190Y318386D01*
X14204Y318428D01*
X14190Y318663D01*
X14176Y318705D01*
X14162Y319149D01*
X14134Y319218D01*
X14093Y319315D01*
X14079Y319371D01*
X14023Y319468D01*
X13968Y319523D01*
X13954Y319551D01*
X13892Y319627D01*
X13864Y319641D01*
X13801Y319704D01*
X13788Y319731D01*
X13753Y319766D01*
X13725Y319780D01*
X13649Y319842D01*
X13614Y319877D01*
X13545Y319904D01*
X13469Y319925D01*
X13295Y320015D01*
X13240Y320029D01*
X13129Y320043D01*
X13087Y320057D01*
X12990Y320099D01*
X12935Y320112D01*
X12754Y320126D01*
X12429Y320147D01*
X11860Y320161D01*
X6479Y320175D01*
X6389Y320182D01*
X6348Y320168D01*
X6098Y320182D01*
X6056Y320168D01*
X5890Y320182D01*
X5848Y320196D01*
X5515Y320210D01*
X5446Y320251D01*
X5370Y320314D01*
X5356Y320341D01*
X5328Y320411D01*
X5321Y320639D01*
X5328Y320716D01*
X5314Y320757D01*
X5293Y320848D01*
X5287Y320952D01*
X5300Y320993D01*
X5293Y321250D01*
X5300Y321368D01*
X5287Y321409D01*
X5293Y321749D01*
X5287Y321867D01*
X5300Y321908D01*
X5293Y322151D01*
X5307Y322207D01*
X5321Y322276D01*
X5328Y322352D01*
X5314Y322380D01*
X5328Y322422D01*
X5342Y322643D01*
X5391Y322706D01*
X5418Y322720D01*
X5446Y322761D01*
X5515Y322789D01*
X5897Y322810D01*
X5952Y322824D01*
X6084Y322831D01*
X6126Y322817D01*
X6375Y322831D01*
X6417Y322817D01*
X6597Y322831D01*
X13295Y322817D01*
D02*
G37*
G36*
X112090D02*
X112853Y322803D01*
X112894Y322789D01*
X113116Y322775D01*
X113213Y322734D01*
X113310Y322706D01*
X113511Y322685D01*
X113567Y322671D01*
X113636Y322643D01*
X113782Y322581D01*
X113879Y322567D01*
X113934Y322553D01*
X114024Y322519D01*
X114045Y322498D01*
X114170Y322442D01*
X114260Y322408D01*
X114337Y322359D01*
X114489Y322290D01*
X114558Y322248D01*
X114614Y322193D01*
X114642Y322179D01*
X114746Y322103D01*
X114753Y322082D01*
X114780Y322068D01*
X114919Y322012D01*
X114947Y321999D01*
X115030Y321915D01*
X115058Y321902D01*
X115106Y321867D01*
X115120Y321839D01*
X115148Y321811D01*
X115155Y321791D01*
X115183Y321777D01*
X115349Y321610D01*
X115370Y321603D01*
X115384Y321576D01*
X115411Y321548D01*
X115418Y321527D01*
X115446Y321513D01*
X115474Y321485D01*
X115501Y321472D01*
X115557Y321388D01*
X115633Y321312D01*
X115689Y321160D01*
X115751Y321083D01*
X115786Y321049D01*
X115800Y321021D01*
X115862Y320945D01*
X115897Y320910D01*
X115945Y320778D01*
X115980Y320730D01*
X116035Y320674D01*
X116049Y320647D01*
X116119Y320549D01*
X116160Y320508D01*
X116188Y320397D01*
X116202Y320286D01*
X116299Y320078D01*
X116327Y319967D01*
X116340Y319870D01*
X116410Y319717D01*
X116431Y319558D01*
X116444Y319475D01*
X116458Y319239D01*
X116472Y319100D01*
X116486Y318975D01*
X116500Y318920D01*
X116542Y318809D01*
X116576Y318719D01*
X116590Y318663D01*
X116576Y318539D01*
X116507Y318386D01*
X116493Y318330D01*
X116479Y318234D01*
X116465Y318178D01*
X116451Y317956D01*
X116431Y317810D01*
X116403Y317672D01*
X116340Y317526D01*
X116327Y317429D01*
X116299Y317318D01*
X116229Y317207D01*
X116202Y317138D01*
X116167Y317048D01*
X116139Y316978D01*
X116119Y316958D01*
X116105Y316930D01*
X116063Y316833D01*
X116042Y316687D01*
X116015Y316618D01*
X115938Y316542D01*
X115883Y316444D01*
X115814Y316375D01*
X115758Y316223D01*
X115675Y316139D01*
X115661Y316112D01*
X115612Y316049D01*
X115585Y316035D01*
X114967Y315418D01*
X114961Y315397D01*
X114933Y315384D01*
X114905Y315356D01*
X114877Y315342D01*
X114808Y315273D01*
X114739Y315245D01*
X114649Y315210D01*
X114565Y315155D01*
X114489Y315120D01*
X114399Y315086D01*
X114323Y315037D01*
X114170Y314968D01*
X114045Y314898D01*
X113920Y314843D01*
X113657Y314718D01*
X113525Y314697D01*
X113414Y314656D01*
X113352Y314635D01*
X113255Y314621D01*
X112728Y314593D01*
X111632Y314579D01*
X110412D01*
X107361Y314593D01*
X107319Y314607D01*
X106945Y314621D01*
X106903Y314635D01*
X106813Y314669D01*
X106695Y314704D01*
X106591Y314725D01*
X106480Y314767D01*
X106390Y314815D01*
X106279Y314843D01*
X106168Y314857D01*
X106071Y314912D01*
X105919Y314981D01*
X105849Y315009D01*
X105752Y315079D01*
X105600Y315134D01*
X105537Y315182D01*
X105524Y315210D01*
X105406Y315287D01*
X105336Y315356D01*
X105281Y315370D01*
X105191Y315404D01*
X105100Y315494D01*
X105031Y315536D01*
X105010Y315557D01*
X104997Y315585D01*
X104934Y315647D01*
X104906Y315661D01*
X104872Y315696D01*
X104858Y315723D01*
X104795Y315786D01*
X104768Y315800D01*
X104747Y315821D01*
X104733Y315848D01*
X104671Y315911D01*
X104643Y315924D01*
X104608Y315959D01*
X104567Y316028D01*
X104497Y316098D01*
X104469Y316167D01*
X104456Y316223D01*
X104359Y316375D01*
X104345Y316431D01*
X104275Y316556D01*
X104220Y316611D01*
X104206Y316639D01*
X104144Y316715D01*
X104095Y316763D01*
X104033Y316937D01*
X103977Y317020D01*
X103943Y317138D01*
X103922Y317256D01*
X103894Y317325D01*
X103859Y317401D01*
X103832Y317471D01*
X103818Y317526D01*
X103804Y317665D01*
X103790Y317776D01*
X103735Y317915D01*
X103721Y317970D01*
X103700Y318199D01*
X103686Y318421D01*
X103679Y318982D01*
X103693Y319024D01*
X103707Y319357D01*
X103721Y319398D01*
X103735Y319495D01*
X103762Y319565D01*
X103790Y319662D01*
X103839Y319960D01*
X103866Y320029D01*
X103929Y320175D01*
X103943Y320272D01*
X103963Y320362D01*
X103984Y320383D01*
X103998Y320411D01*
X104053Y320466D01*
X104067Y320494D01*
X104130Y320570D01*
X104151Y320591D01*
X104164Y320619D01*
X104220Y320743D01*
X104275Y320841D01*
X104345Y320993D01*
X104393Y321083D01*
X104421Y321097D01*
X104442Y321118D01*
X104456Y321146D01*
X104518Y321222D01*
X104594Y321284D01*
X104657Y321361D01*
X104733Y321423D01*
X104795Y321499D01*
X104823Y321513D01*
X104872Y321562D01*
X104886Y321590D01*
X104934Y321638D01*
X104962Y321652D01*
X105010Y321700D01*
X105024Y321728D01*
X105059Y321763D01*
X105087Y321777D01*
X105135Y321825D01*
X105149Y321853D01*
X105198Y321902D01*
X105225Y321915D01*
X105274Y321964D01*
X105288Y321992D01*
X105322Y322026D01*
X105350Y322040D01*
X105378Y322068D01*
X105406Y322082D01*
X105420Y322109D01*
X105447Y322123D01*
X105475Y322151D01*
X105551Y322172D01*
X105634Y322214D01*
X105718Y322269D01*
X105829Y322311D01*
X105898Y322338D01*
X105933Y322373D01*
X105960Y322387D01*
X106057Y322429D01*
X106127Y322456D01*
X106154Y322470D01*
X106252Y322539D01*
X106383Y322588D01*
X106453Y322616D01*
X106543Y322664D01*
X106598Y322678D01*
X106792Y322706D01*
X106938Y322741D01*
X107007Y322768D01*
X107077Y322782D01*
X107271Y322796D01*
X107507Y322810D01*
X108075Y322824D01*
X112048Y322831D01*
X112090Y322817D01*
D02*
G37*
G36*
X94644D02*
X94686Y322803D01*
X95060Y322789D01*
X95102Y322775D01*
X95171Y322761D01*
X95240Y322734D01*
X95296Y322720D01*
X95490Y322692D01*
X95636Y322657D01*
X95809Y322581D01*
X95906Y322567D01*
X95962Y322553D01*
X96052Y322519D01*
X96073Y322498D01*
X96100Y322484D01*
X96197Y322442D01*
X96287Y322408D01*
X96364Y322359D01*
X96516Y322290D01*
X96586Y322248D01*
X96641Y322193D01*
X96669Y322179D01*
X96773Y322103D01*
X96780Y322082D01*
X96808Y322068D01*
X96946Y322012D01*
X96974Y321999D01*
X97057Y321915D01*
X97085Y321902D01*
X97134Y321867D01*
X97147Y321839D01*
X97175Y321811D01*
X97182Y321791D01*
X97210Y321777D01*
X97827Y321160D01*
X97841Y321132D01*
X97924Y321049D01*
X97952Y320979D01*
X97965Y320924D01*
X98063Y320771D01*
X98076Y320716D01*
X98174Y320536D01*
X98215Y320438D01*
X98243Y320369D01*
X98298Y320272D01*
X98340Y320175D01*
X98361Y320043D01*
X98402Y319932D01*
X98437Y319856D01*
X98451Y319800D01*
X98465Y319704D01*
X98479Y319648D01*
X98499Y319405D01*
X98513Y319350D01*
X98576Y319149D01*
X98596Y318975D01*
X98610Y318726D01*
X98617Y318691D01*
X98603Y318650D01*
X98590Y318330D01*
X98576Y318289D01*
X98562Y318192D01*
X98534Y318123D01*
X98506Y318025D01*
X98492Y317970D01*
X98472Y317727D01*
X98458Y317644D01*
X98444Y317575D01*
X98416Y317505D01*
X98382Y317429D01*
X98354Y317332D01*
X98333Y317214D01*
X98305Y317145D01*
X98285Y317124D01*
X98215Y316971D01*
X98181Y316881D01*
X98132Y316819D01*
X98118Y316791D01*
X98090Y316722D01*
X98056Y316632D01*
X97979Y316556D01*
X97965Y316528D01*
X97868Y316403D01*
X97841Y316375D01*
X97792Y316243D01*
X97758Y316195D01*
X97702Y316139D01*
X97688Y316112D01*
X97660Y316084D01*
X97654Y316063D01*
X97626Y316049D01*
X96932Y315356D01*
X96905Y315342D01*
X96835Y315273D01*
X96766Y315245D01*
X96676Y315210D01*
X96613Y315148D01*
X96586Y315134D01*
X96558Y315106D01*
X96489Y315065D01*
X96419Y314995D01*
X96246Y314933D01*
X96225Y314912D01*
X96197Y314898D01*
X96100Y314857D01*
X96003Y314843D01*
X95948Y314829D01*
X95858Y314794D01*
X95767Y314746D01*
X95670Y314718D01*
X95573Y314704D01*
X95442Y314656D01*
X95379Y314635D01*
X95282Y314621D01*
X94755Y314593D01*
X93660Y314579D01*
X86226Y314565D01*
X86185Y314552D01*
X85727Y314538D01*
X85686Y314524D01*
X85575Y314510D01*
X85478Y314468D01*
X85367Y314441D01*
X85283Y314427D01*
X85103Y314343D01*
X85006Y314316D01*
X84909Y314302D01*
X84819Y314267D01*
X84715Y314205D01*
X84583Y314156D01*
X84507Y314108D01*
X84354Y314038D01*
X84229Y313969D01*
X84105Y313914D01*
X84008Y313858D01*
X83980Y313830D01*
X83952Y313817D01*
X83910Y313775D01*
X83883Y313761D01*
X83834Y313713D01*
X83820Y313685D01*
X83786Y313650D01*
X83758Y313636D01*
X83695Y313574D01*
X83682Y313546D01*
X83661Y313525D01*
X83633Y313511D01*
X83571Y313449D01*
X83557Y313421D01*
X83522Y313387D01*
X83494Y313373D01*
X83432Y313310D01*
X83418Y313283D01*
X83384Y313248D01*
X83356Y313234D01*
X83307Y313186D01*
X83293Y313158D01*
X83252Y313116D01*
X83238Y313088D01*
X83196Y313047D01*
X83148Y312915D01*
X83099Y312839D01*
X83030Y312686D01*
X83002Y312617D01*
X82933Y312520D01*
X82884Y312388D01*
X82815Y312277D01*
X82780Y312201D01*
X82746Y312111D01*
X82718Y312041D01*
X82697Y312021D01*
X82683Y311993D01*
X82655Y311924D01*
X82641Y311826D01*
X82628Y311771D01*
X82593Y311681D01*
X82558Y311563D01*
X82544Y311424D01*
X82531Y311244D01*
X82510Y310987D01*
X82503Y310842D01*
X82517Y310800D01*
X82537Y310474D01*
X82551Y310322D01*
X82565Y310239D01*
X82607Y310128D01*
X82628Y310051D01*
X82641Y309996D01*
X82662Y309892D01*
X82690Y309823D01*
X82766Y309649D01*
X82794Y309483D01*
X82850Y309386D01*
X82891Y309289D01*
X82919Y309219D01*
X82961Y309150D01*
X83030Y309081D01*
X83071Y309011D01*
X83141Y308942D01*
X83168Y308873D01*
X83203Y308783D01*
X83238Y308734D01*
X83293Y308678D01*
X83307Y308651D01*
X83508Y308450D01*
X83536Y308436D01*
X83557Y308415D01*
X83571Y308387D01*
X83647Y308311D01*
X83675Y308297D01*
X83695Y308276D01*
X83709Y308249D01*
X83786Y308172D01*
X83813Y308158D01*
X83834Y308138D01*
X83848Y308110D01*
X83910Y308048D01*
X83938Y308034D01*
X84008Y307964D01*
X84035Y307950D01*
X84105Y307923D01*
X84160Y307909D01*
X84236Y307846D01*
X84285Y307798D01*
X84313Y307784D01*
X84389Y307722D01*
X84424Y307687D01*
X84493Y307659D01*
X84625Y307611D01*
X84645Y307590D01*
X84673Y307576D01*
X84770Y307534D01*
X84867Y307521D01*
X84944Y307500D01*
X85013Y307472D01*
X85186Y307396D01*
X85318Y307375D01*
X85519Y307313D01*
X85658Y307299D01*
X86039Y307278D01*
X86594Y307264D01*
X132150Y307250D01*
X132691Y307236D01*
X132940Y307222D01*
X133211Y307202D01*
X133280Y307174D01*
X133377Y307146D01*
X133474Y307132D01*
X133689Y307111D01*
X133772Y307098D01*
X133828Y307084D01*
X133897Y307056D01*
X133973Y307021D01*
X134084Y306994D01*
X134188Y306973D01*
X134258Y306945D01*
X134278Y306924D01*
X134431Y306855D01*
X134521Y306820D01*
X134542Y306799D01*
X134570Y306786D01*
X134722Y306716D01*
X134847Y306647D01*
X134875Y306619D01*
X134951Y306598D01*
X135021Y306571D01*
X135069Y306536D01*
X135125Y306480D01*
X135152Y306467D01*
X135180Y306439D01*
X135208Y306425D01*
X135242Y306376D01*
X135305Y306314D01*
X135332Y306300D01*
X135402Y306231D01*
X135429Y306217D01*
X135499Y306189D01*
X135554Y306175D01*
X135631Y306113D01*
X135679Y306064D01*
X135707Y306050D01*
X135769Y305988D01*
X135783Y305960D01*
X135818Y305912D01*
X135846Y305898D01*
X135880Y305836D01*
X135929Y305704D01*
X136005Y305628D01*
X136019Y305600D01*
X136109Y305510D01*
X136137Y305496D01*
X136192Y305413D01*
X136269Y305336D01*
X136331Y305163D01*
X136366Y305128D01*
X136379Y305101D01*
X136435Y304976D01*
X136463Y304907D01*
X136532Y304809D01*
X136546Y304754D01*
X136574Y304685D01*
X136671Y304477D01*
X136699Y304282D01*
X136719Y304165D01*
X136768Y304005D01*
X136782Y303908D01*
X136803Y303651D01*
X136816Y303291D01*
X136823Y302868D01*
X136809Y302826D01*
X136796Y302355D01*
X136782Y302313D01*
X136768Y302091D01*
X136740Y302022D01*
X136712Y301925D01*
X136685Y301731D01*
X136664Y301627D01*
X136636Y301557D01*
X136615Y301537D01*
X136560Y301398D01*
X136525Y301308D01*
X136504Y301287D01*
X136490Y301259D01*
X136463Y301231D01*
X136393Y301051D01*
X136310Y300968D01*
X136296Y300940D01*
X136234Y300864D01*
X136213Y300843D01*
X136199Y300815D01*
X136158Y300718D01*
X136102Y300621D01*
X136033Y300552D01*
X136019Y300524D01*
X135804Y300309D01*
X135783Y300302D01*
X135769Y300275D01*
X135679Y300184D01*
X135658Y300177D01*
X135645Y300150D01*
X135416Y299921D01*
X135388Y299907D01*
X135353Y299858D01*
X135291Y299796D01*
X135263Y299782D01*
X135180Y299699D01*
X135111Y299671D01*
X135021Y299637D01*
X134937Y299581D01*
X134861Y299547D01*
X134771Y299512D01*
X134694Y299463D01*
X134570Y299408D01*
X134417Y299325D01*
X134265Y299255D01*
X134057Y299158D01*
X133862Y299130D01*
X133745Y299110D01*
X133585Y299061D01*
X133530Y299047D01*
X133162Y299027D01*
X132594Y299013D01*
X103596Y298999D01*
X103589Y298992D01*
X103547Y299006D01*
X103325Y298992D01*
X102632Y298978D01*
X102590Y298964D01*
X102271Y298950D01*
X102230Y298936D01*
X102161Y298909D01*
X102064Y298881D01*
X101925Y298867D01*
X101869Y298853D01*
X101758Y298839D01*
X101578Y298756D01*
X101523Y298742D01*
X101405Y298721D01*
X101315Y298687D01*
X101162Y298617D01*
X101107Y298603D01*
X100996Y298590D01*
X100871Y298520D01*
X100774Y298479D01*
X100684Y298444D01*
X100600Y298375D01*
X100580Y298354D01*
X100552Y298340D01*
X100524Y298312D01*
X100503Y298305D01*
X100490Y298278D01*
X100399Y298188D01*
X100372Y298174D01*
X100302Y298104D01*
X100233Y298076D01*
X100143Y298042D01*
X100094Y298007D01*
X100025Y297938D01*
X99997Y297924D01*
X99921Y297848D01*
X99907Y297820D01*
X99859Y297785D01*
X99810Y297737D01*
X99796Y297709D01*
X99754Y297667D01*
X99748Y297647D01*
X99727Y297640D01*
X99713Y297612D01*
X99685Y297543D01*
X99650Y297453D01*
X99560Y297362D01*
X99546Y297335D01*
X99484Y297258D01*
X99449Y297224D01*
X99422Y297154D01*
X99387Y297064D01*
X99332Y296981D01*
X99269Y296835D01*
X99214Y296738D01*
X99130Y296558D01*
X99061Y296406D01*
X99047Y296350D01*
X99026Y296177D01*
X98999Y295899D01*
X98985Y295816D01*
X98971Y295747D01*
X98957Y295691D01*
X98936Y295615D01*
X98922Y295560D01*
X98895Y295393D01*
X98881Y295254D01*
X98895Y295157D01*
X98916Y295026D01*
X98929Y294956D01*
X98943Y294901D01*
X98978Y294783D01*
X98992Y294727D01*
X99006Y294630D01*
X99019Y294492D01*
X99040Y294360D01*
X99054Y294305D01*
X99096Y294193D01*
X99130Y294103D01*
X99144Y294048D01*
X99165Y293930D01*
X99193Y293861D01*
X99214Y293840D01*
X99255Y293743D01*
X99290Y293653D01*
X99311Y293604D01*
X99380Y293535D01*
X99394Y293507D01*
X99422Y293479D01*
X99463Y293410D01*
X99484Y293389D01*
X99505Y293382D01*
X99519Y293354D01*
X99546Y293285D01*
X99581Y293195D01*
X99657Y293119D01*
X99671Y293091D01*
X99838Y292925D01*
X99845Y292904D01*
X99872Y292890D01*
X100101Y292661D01*
X100108Y292640D01*
X100136Y292626D01*
X100302Y292460D01*
X100330Y292446D01*
X100399Y292377D01*
X100552Y292321D01*
X100635Y292238D01*
X100663Y292224D01*
X100788Y292127D01*
X100912Y292072D01*
X101037Y292002D01*
X101065Y291975D01*
X101120Y291961D01*
X101190Y291933D01*
X101426Y291822D01*
X101550Y291808D01*
X101620Y291780D01*
X101758Y291739D01*
X101814Y291725D01*
X102258Y291711D01*
X102299Y291697D01*
X102764Y291690D01*
X102799Y291697D01*
X102840Y291683D01*
X113241Y291670D01*
X113283Y291656D01*
X113699Y291642D01*
X113740Y291628D01*
X113816Y291607D01*
X113907Y291572D01*
X114101Y291545D01*
X114212Y291531D01*
X114281Y291503D01*
X114434Y291434D01*
X114531Y291420D01*
X114621Y291399D01*
X114690Y291371D01*
X114711Y291351D01*
X114739Y291337D01*
X114864Y291281D01*
X114954Y291247D01*
X114974Y291226D01*
X115002Y291212D01*
X115071Y291170D01*
X115162Y291136D01*
X115231Y291108D01*
X115266Y291073D01*
X115293Y291059D01*
X115391Y291018D01*
X115460Y290990D01*
X115536Y290928D01*
X115571Y290893D01*
X115598Y290879D01*
X115661Y290817D01*
X115675Y290789D01*
X115709Y290754D01*
X115737Y290740D01*
X115814Y290678D01*
X115848Y290643D01*
X116001Y290588D01*
X116174Y290415D01*
X116195Y290338D01*
X116223Y290269D01*
X116299Y290193D01*
X116313Y290165D01*
X116375Y290089D01*
X116403Y290075D01*
X116479Y289998D01*
X116486Y289978D01*
X116514Y289964D01*
X116590Y289888D01*
X116604Y289860D01*
X116687Y289777D01*
X116715Y289707D01*
X116750Y289617D01*
X116784Y289569D01*
X116854Y289499D01*
X116895Y289430D01*
X116958Y289354D01*
X116978Y289291D01*
X116992Y289194D01*
X117006Y289111D01*
X117075Y289014D01*
X117110Y288924D01*
X117152Y288813D01*
X117179Y288743D01*
X117200Y288681D01*
X117214Y288626D01*
X117235Y288244D01*
X117256Y287419D01*
X117242Y287377D01*
X117235Y287010D01*
X117242Y286878D01*
X117228Y286837D01*
X117207Y286455D01*
X117193Y286386D01*
X117166Y286317D01*
X117131Y286199D01*
X117117Y286143D01*
X117103Y286046D01*
X117048Y285949D01*
X116992Y285824D01*
X116909Y285672D01*
X116854Y285547D01*
X116770Y285394D01*
X116729Y285297D01*
X116659Y285173D01*
X116590Y285103D01*
X116576Y285075D01*
X116500Y284999D01*
X116472Y284985D01*
X116438Y284937D01*
X116389Y284888D01*
X116361Y284874D01*
X116327Y284840D01*
X116313Y284812D01*
X116250Y284750D01*
X116223Y284736D01*
X116202Y284715D01*
X116188Y284687D01*
X116112Y284611D01*
X116084Y284597D01*
X116063Y284576D01*
X116049Y284548D01*
X115848Y284347D01*
X115820Y284333D01*
X115800Y284313D01*
X115786Y284285D01*
X115723Y284223D01*
X115696Y284209D01*
X115612Y284125D01*
X115543Y284098D01*
X115453Y284063D01*
X115404Y284028D01*
X115391Y284001D01*
X115363Y283987D01*
X115238Y283890D01*
X115196Y283848D01*
X115023Y283786D01*
X115002Y283765D01*
X114877Y283709D01*
X114822Y283696D01*
X114690Y283675D01*
X114489Y283571D01*
X114350Y283515D01*
X114226Y283460D01*
X114052Y283439D01*
X113900Y283425D01*
X113775Y283411D01*
X113595Y283384D01*
X113539Y283370D01*
X113477Y283349D01*
X113338Y283335D01*
X112811Y283307D01*
X112305Y283300D01*
X112284Y283307D01*
X112242Y283293D01*
X95275Y283286D01*
X95240Y283293D01*
X95199Y283279D01*
X94589Y283266D01*
X94547Y283252D01*
X94270Y283238D01*
X94145Y283182D01*
X94076Y283155D01*
X93951Y283085D01*
X93826Y283030D01*
X93673Y282947D01*
X93549Y282891D01*
X93396Y282808D01*
X93299Y282766D01*
X93174Y282697D01*
X93119Y282642D01*
X93091Y282628D01*
X93042Y282593D01*
X93029Y282565D01*
X92952Y282489D01*
X92925Y282475D01*
X92841Y282392D01*
X92772Y282364D01*
X92682Y282330D01*
X92564Y282212D01*
X92543Y282205D01*
X92529Y282177D01*
X92488Y282080D01*
X92432Y281983D01*
X92363Y281914D01*
X92321Y281844D01*
X92252Y281775D01*
X92197Y281622D01*
X92148Y281560D01*
X92127Y281553D01*
X92113Y281525D01*
X92016Y281400D01*
X91988Y281373D01*
X91961Y281303D01*
X91926Y281213D01*
X91850Y281068D01*
X91836Y281012D01*
X91822Y280915D01*
X91774Y280783D01*
X91711Y280638D01*
X91690Y280450D01*
X91676Y280367D01*
X91663Y280312D01*
X91621Y280201D01*
X91607Y280145D01*
X91593Y280062D01*
X91566Y279729D01*
X91559Y279681D01*
X91572Y279639D01*
X91593Y279341D01*
X91607Y279258D01*
X91621Y279202D01*
X91649Y279133D01*
X91670Y279057D01*
X91683Y279001D01*
X91697Y278863D01*
X91711Y278807D01*
X91725Y278710D01*
X91808Y278530D01*
X91857Y278315D01*
X91947Y278141D01*
X91981Y278051D01*
X92016Y278003D01*
X92044Y277975D01*
X92058Y277947D01*
X92086Y277920D01*
X92099Y277892D01*
X92127Y277864D01*
X92141Y277836D01*
X92210Y277767D01*
X92231Y277691D01*
X92259Y277621D01*
X92335Y277545D01*
X92349Y277517D01*
X92377Y277490D01*
X92391Y277462D01*
X92439Y277427D01*
X92515Y277351D01*
X92522Y277330D01*
X92550Y277316D01*
X92779Y277087D01*
X92793Y277060D01*
X92841Y277025D01*
X92918Y276949D01*
X92925Y276928D01*
X92952Y276914D01*
X93042Y276824D01*
X93049Y276803D01*
X93077Y276789D01*
X93119Y276748D01*
X93146Y276734D01*
X93216Y276665D01*
X93389Y276602D01*
X93410Y276581D01*
X93438Y276567D01*
X93465Y276540D01*
X93521Y276526D01*
X93618Y276484D01*
X93757Y276401D01*
X93826Y276373D01*
X93916Y276339D01*
X94062Y276262D01*
X94117Y276248D01*
X94235Y276228D01*
X94346Y276186D01*
X94506Y276138D01*
X94603Y276124D01*
X94908Y276110D01*
X94949Y276096D01*
X95150Y276075D01*
X95233Y276061D01*
X95344Y276034D01*
X95497Y276020D01*
X96114Y275985D01*
X97418Y275971D01*
X107458Y275957D01*
X107500Y275943D01*
X107874Y275930D01*
X107943Y275902D01*
X108041Y275860D01*
X108138Y275846D01*
X108193Y275833D01*
X108269Y275812D01*
X108429Y275735D01*
X108526Y275708D01*
X108637Y275694D01*
X108734Y275638D01*
X108886Y275569D01*
X108956Y275541D01*
X109053Y275472D01*
X109185Y275423D01*
X109254Y275382D01*
X109268Y275354D01*
X109330Y275306D01*
X109358Y275292D01*
X109406Y275243D01*
X109420Y275215D01*
X109455Y275181D01*
X109483Y275167D01*
X109559Y275104D01*
X109608Y275056D01*
X109712Y275035D01*
X109760Y275014D01*
X109781Y274993D01*
X109795Y274938D01*
X109816Y274848D01*
X109850Y274799D01*
X109927Y274778D01*
X109996Y274765D01*
X110044Y274730D01*
X110072Y274633D01*
X110086Y274577D01*
X110169Y274494D01*
X110183Y274466D01*
X110246Y274390D01*
X110322Y274328D01*
X110384Y274238D01*
X110412Y274224D01*
X110433Y274203D01*
X110461Y274134D01*
X110474Y274078D01*
X110530Y273981D01*
X110557Y273953D01*
X110585Y273884D01*
X110620Y273794D01*
X110689Y273683D01*
X110724Y273607D01*
X110772Y273475D01*
X110793Y273454D01*
X110849Y273329D01*
X110863Y273232D01*
X110877Y273177D01*
X110946Y272997D01*
X110960Y272941D01*
X110981Y272754D01*
X110994Y272643D01*
X111008Y272449D01*
X111022Y272282D01*
X111036Y272213D01*
X111078Y272102D01*
X111105Y272033D01*
X111126Y271956D01*
X111112Y271804D01*
X111057Y271679D01*
X111015Y271513D01*
X110994Y271187D01*
X110967Y270965D01*
X110953Y270840D01*
X110877Y270653D01*
X110863Y270556D01*
X110849Y270500D01*
X110814Y270410D01*
X110738Y270237D01*
X110717Y270105D01*
X110689Y270036D01*
X110627Y269932D01*
X110571Y269779D01*
X110509Y269703D01*
X110474Y269668D01*
X110461Y269641D01*
X110398Y269564D01*
X110363Y269529D01*
X110336Y269460D01*
X110301Y269370D01*
X110211Y269280D01*
X110169Y269211D01*
X110148Y269190D01*
X110121Y269176D01*
X110058Y269114D01*
X110044Y269086D01*
X110024Y269065D01*
X109996Y269051D01*
X109906Y268961D01*
X109899Y268940D01*
X109871Y268926D01*
X109767Y268822D01*
X109760Y268801D01*
X109732Y268788D01*
X109656Y268711D01*
X109642Y268684D01*
X109621Y268663D01*
X109594Y268649D01*
X109531Y268587D01*
X109517Y268559D01*
X109483Y268524D01*
X109455Y268510D01*
X109393Y268448D01*
X109379Y268420D01*
X109344Y268385D01*
X109316Y268372D01*
X109240Y268309D01*
X109205Y268274D01*
X109074Y268226D01*
X109025Y268205D01*
X108997Y268177D01*
X108970Y268164D01*
X108873Y268122D01*
X108803Y268094D01*
X108706Y268039D01*
X108609Y267997D01*
X108512Y267983D01*
X108436Y267962D01*
X108366Y267935D01*
X108304Y267914D01*
X108249Y267900D01*
X108068Y267886D01*
X107638Y267872D01*
X107292Y267858D01*
X66388Y267852D01*
X66326Y267858D01*
X66284Y267845D01*
X66056Y267852D01*
X65813Y267845D01*
X65785Y267858D01*
X65743Y267845D01*
X65203Y267803D01*
X65120Y267789D01*
X65036Y267734D01*
X65009Y267720D01*
X64932Y267657D01*
X64849Y267477D01*
X64828Y267151D01*
X64814Y266957D01*
X64808Y266742D01*
X64821Y266714D01*
X64808Y266673D01*
X64801Y266000D01*
X64808Y263247D01*
X64794Y263206D01*
X64780Y262041D01*
X64766Y261999D01*
X64752Y261653D01*
X64683Y261500D01*
X64648Y261410D01*
X64620Y261354D01*
X64592Y261341D01*
X64516Y261264D01*
X64502Y261236D01*
X64426Y261202D01*
X64294Y261153D01*
X64218Y261119D01*
X64121Y261105D01*
X63740Y261084D01*
X63171Y261070D01*
X53790Y261063D01*
X53748Y261077D01*
X52999Y261091D01*
X52957Y261105D01*
X52722Y261119D01*
X52569Y261188D01*
X52479Y261223D01*
X52403Y261299D01*
X52375Y261313D01*
X52299Y261375D01*
X52243Y261458D01*
X52229Y261486D01*
X52188Y261583D01*
X52181Y261798D01*
X52188Y261902D01*
X52174Y261944D01*
X52160Y261999D01*
X52167Y262214D01*
X52146Y262360D01*
X52160Y262401D01*
X52153Y262644D01*
X52160Y262817D01*
X52146Y262859D01*
X52160Y263067D01*
X52146Y263109D01*
X52132Y264662D01*
X52118Y264704D01*
X52105Y265106D01*
X52049Y265231D01*
X52021Y265300D01*
X52007Y265355D01*
X51938Y265452D01*
X51834Y265556D01*
X51779Y265570D01*
X51744Y265577D01*
X51688Y265563D01*
X51605Y265494D01*
X51522Y265411D01*
X51494Y265341D01*
X51446Y265210D01*
X51411Y265119D01*
X51397Y265064D01*
X51383Y264634D01*
X51370Y264593D01*
X51356Y263497D01*
X51349Y262408D01*
X51356Y262290D01*
X51342Y262249D01*
X51349Y262020D01*
X51335Y261951D01*
X51321Y261729D01*
X51307Y261549D01*
X51203Y261375D01*
X51155Y261327D01*
X51127Y261313D01*
X51044Y261230D01*
X50974Y261202D01*
X50842Y261153D01*
X50766Y261119D01*
X50711Y261105D01*
X50274Y261084D01*
X49719Y261070D01*
X45940Y261063D01*
X45899Y261077D01*
X45136Y261091D01*
X45094Y261105D01*
X44872Y261119D01*
X44748Y261174D01*
X44658Y261209D01*
X44581Y261257D01*
X44526Y261313D01*
X44498Y261327D01*
X44422Y261403D01*
X44408Y261431D01*
X44352Y261514D01*
X44338Y261569D01*
X44318Y261937D01*
X44304Y262006D01*
X44297Y262110D01*
X44311Y262152D01*
X44297Y262401D01*
X44311Y262443D01*
X44297Y262665D01*
X44290Y266083D01*
X44297Y266243D01*
X44283Y266284D01*
X44297Y266520D01*
X44283Y266562D01*
X44269Y266659D01*
X44248Y267054D01*
X44234Y267137D01*
X44200Y267214D01*
X44137Y267387D01*
X44117Y267408D01*
X44103Y267435D01*
X44033Y267505D01*
X44019Y267533D01*
X43957Y267595D01*
X43888Y267637D01*
X43846Y267678D01*
X43777Y267706D01*
X43576Y267741D01*
X43527Y267775D01*
X43402Y267831D01*
X43278Y267817D01*
X43180Y267747D01*
X43111Y267720D01*
X43021Y267685D01*
X42959Y267623D01*
X42931Y267609D01*
X42903Y267581D01*
X42875Y267567D01*
X42827Y267519D01*
X42813Y267491D01*
X42778Y267456D01*
X42751Y267442D01*
X42702Y267394D01*
X42647Y267297D01*
X42619Y267227D01*
X42605Y267172D01*
X42619Y267117D01*
X42605Y266978D01*
X42577Y266631D01*
X42563Y266590D01*
X42577Y266493D01*
X42570Y266264D01*
X42577Y266104D01*
X42563Y266063D01*
X42570Y265889D01*
X42557Y264988D01*
X42550Y264939D01*
X42563Y264898D01*
X42550Y264717D01*
X42529Y264170D01*
X42515Y264059D01*
X42487Y263989D01*
X42439Y263871D01*
X42425Y263816D01*
X42362Y263740D01*
X42328Y263705D01*
X42314Y263677D01*
X42251Y263601D01*
X42127Y263504D01*
X41877Y263393D01*
X41766Y263365D01*
X41315Y263344D01*
X41267Y263337D01*
X41225Y263351D01*
X41045Y263337D01*
X39616Y263324D01*
X39270Y263337D01*
X38819Y263344D01*
X38757Y263337D01*
X38715Y263351D01*
X38264Y263372D01*
X38209Y263386D01*
X38063Y263449D01*
X37973Y263483D01*
X37952Y263504D01*
X37925Y263518D01*
X37855Y263587D01*
X37827Y263601D01*
X37765Y263663D01*
X37751Y263691D01*
X37682Y263761D01*
X37668Y263788D01*
X37626Y263885D01*
X37592Y263975D01*
X37557Y264052D01*
X37543Y264190D01*
X37515Y265119D01*
X37502Y266423D01*
X37488Y267657D01*
X37439Y267706D01*
X37349Y267727D01*
X37238Y267768D01*
X37162Y267803D01*
X36794Y267824D01*
X36572Y267838D01*
X35726Y267852D01*
X29840Y267858D01*
X29798Y267845D01*
X28772Y267831D01*
X28730Y267817D01*
X28390Y267796D01*
X28321Y267768D01*
X28245Y267734D01*
X28155Y267713D01*
X28106Y267692D01*
X28071Y267657D01*
X28058Y267560D01*
X28051Y263643D01*
X28058Y263469D01*
X28044Y263428D01*
X28058Y263220D01*
X28044Y263178D01*
X28051Y262949D01*
X28037Y262894D01*
X28023Y262810D01*
X28016Y262748D01*
X28030Y262720D01*
X28016Y262679D01*
X28002Y262457D01*
X27940Y262381D01*
X27884Y262325D01*
X27787Y262297D01*
X27434Y262277D01*
X27364Y262263D01*
X27302Y262256D01*
X27260Y262270D01*
X27170Y262277D01*
X27059Y262263D01*
X27038Y262256D01*
X26997Y262270D01*
X26740Y262263D01*
X26553Y262270D01*
X26511Y262256D01*
X26331Y262270D01*
X26290Y262256D01*
X20236Y262263D01*
X20118Y262256D01*
X20077Y262270D01*
X19848Y262263D01*
X19633Y262270D01*
X19605Y262256D01*
X19564Y262270D01*
X19473Y262277D01*
X19362Y262263D01*
X19300Y262256D01*
X19259Y262270D01*
X19161Y262284D01*
X18836Y262304D01*
X18766Y262332D01*
X18669Y262429D01*
X18641Y262498D01*
X18628Y262887D01*
X18614Y262928D01*
X18600Y262984D01*
X18614Y263164D01*
X18600Y263303D01*
X18614Y263400D01*
X18600Y263580D01*
X18614Y263691D01*
X18600Y263733D01*
Y265660D01*
Y265674D01*
X18607Y266610D01*
X18600Y266770D01*
X18614Y266811D01*
X18600Y267033D01*
X18614Y267075D01*
X18607Y267304D01*
X18621Y267359D01*
X18634Y267428D01*
X18648Y267775D01*
X18718Y267886D01*
X18766Y267962D01*
X18787Y267983D01*
X18884Y268039D01*
X18981Y268080D01*
X19224Y268087D01*
X19272Y268080D01*
X19314Y268094D01*
X19418Y268115D01*
X19522Y268122D01*
X19564Y268108D01*
X19813Y268122D01*
X19855Y268108D01*
X20077Y268122D01*
X20153Y268115D01*
X24369Y268129D01*
X24417Y268150D01*
X24438Y268171D01*
X24452Y268226D01*
X24466Y268323D01*
X24452Y274161D01*
X24403Y274224D01*
X24306Y274238D01*
X20264Y274245D01*
X20104Y274238D01*
X20063Y274251D01*
X19834Y274245D01*
X19661Y274251D01*
X19619Y274238D01*
X19522Y274251D01*
X19293Y274245D01*
X19224Y274258D01*
X18988Y274272D01*
X18822Y274286D01*
X18745Y274335D01*
X18655Y274425D01*
X18641Y274522D01*
X18614Y274924D01*
X18600Y274966D01*
X18614Y275243D01*
X18600Y275285D01*
X18614Y275507D01*
X18628Y275548D01*
X18648Y275902D01*
X18683Y275950D01*
X18704Y275985D01*
X18731Y275999D01*
X18773Y276040D01*
X18842Y276068D01*
X19210Y276089D01*
X19265Y276103D01*
X19383Y276110D01*
X19425Y276096D01*
X19668Y276103D01*
X19799Y276096D01*
X19841Y276110D01*
X19973Y276103D01*
X19993Y276110D01*
X20007Y276096D01*
X20049Y276110D01*
X24390Y276124D01*
X24438Y276158D01*
X24466Y276269D01*
X24452Y282149D01*
X24403Y282212D01*
X24306Y282225D01*
X20084Y282232D01*
X19952Y282225D01*
X19910Y282239D01*
X19695Y282232D01*
X19612Y282246D01*
X19605Y282253D01*
X19564Y282239D01*
X19425Y282225D01*
X19383Y282239D01*
X19272Y282267D01*
X18926Y282281D01*
X18898Y282309D01*
X18870Y282323D01*
X18752Y282399D01*
X18738Y282427D01*
X18669Y282524D01*
X18641Y282593D01*
X18621Y282960D01*
X18607Y283044D01*
X18600Y283217D01*
X18614Y283259D01*
X18600Y283536D01*
X18614Y283578D01*
X18628Y283758D01*
X18655Y284049D01*
X18773Y284167D01*
X18884Y284195D01*
X18960Y284188D01*
X19196Y284202D01*
X19252Y284216D01*
X19411Y284223D01*
X19453Y284209D01*
X19633Y284223D01*
X24376Y284236D01*
X24438Y284285D01*
X24452Y284340D01*
X24466Y284438D01*
X24452Y290276D01*
X24424Y290304D01*
X24417Y290324D01*
X24320Y290352D01*
X19848Y290359D01*
X19675Y290352D01*
X19633Y290366D01*
X19397Y290352D01*
X19328Y290380D01*
X18939Y290394D01*
X18842Y290463D01*
X18773Y290505D01*
X18738Y290539D01*
X18724Y290567D01*
X18655Y290678D01*
X18641Y290734D01*
X18621Y291018D01*
X18607Y291157D01*
X18600Y291455D01*
X18614Y291496D01*
X18628Y291857D01*
X18641Y291898D01*
X18655Y292037D01*
X18724Y292190D01*
X18745Y292280D01*
X18766Y292301D01*
X18773Y292321D01*
X18842Y292349D01*
X24403Y292363D01*
X24438Y292398D01*
X24452Y292453D01*
X24466Y292550D01*
X24452Y298389D01*
X24403Y298451D01*
X24348Y298465D01*
X19931Y298472D01*
X19841Y298465D01*
X19799Y298479D01*
X19570Y298472D01*
X19501Y298486D01*
X19453Y298493D01*
X19411Y298479D01*
X19314Y298465D01*
X19147Y298506D01*
X18787Y298520D01*
X18655Y298652D01*
X18641Y298749D01*
X18628Y299096D01*
X18614Y299137D01*
X18600Y299193D01*
X18614Y299373D01*
X18600Y299512D01*
X18614Y299609D01*
X18600Y299789D01*
X18614Y299914D01*
X18600Y299956D01*
X18614Y321978D01*
X18628Y322019D01*
X18648Y322470D01*
X18662Y322526D01*
X18711Y322643D01*
X18738Y322741D01*
X18780Y322810D01*
X18856Y322831D01*
X94644Y322817D01*
D02*
G37*
G36*
X21907Y297785D02*
X21949Y297771D01*
X22143Y297757D01*
X22295Y297688D01*
X22365Y297661D01*
X22490Y297591D01*
X22615Y297536D01*
X22739Y297466D01*
X22864Y297411D01*
X22989Y297341D01*
X23017Y297300D01*
X23044Y297286D01*
X23121Y297224D01*
X23183Y297134D01*
X23211Y297120D01*
X23232Y297099D01*
X23259Y297029D01*
X23280Y296953D01*
X23315Y296905D01*
X23384Y296835D01*
X23398Y296808D01*
X23460Y296731D01*
X23495Y296697D01*
X23509Y296669D01*
X23537Y296600D01*
X23571Y296509D01*
X23634Y296406D01*
X23661Y296294D01*
X23682Y296177D01*
X23745Y296017D01*
X23772Y295823D01*
X23793Y295428D01*
X23800Y295282D01*
X23786Y295240D01*
X23772Y294852D01*
X23759Y294811D01*
X23745Y294658D01*
X23675Y294506D01*
X23641Y294415D01*
X23592Y294339D01*
X23523Y294187D01*
X23454Y294062D01*
X23398Y293937D01*
X23342Y293840D01*
X23287Y293784D01*
X23273Y293757D01*
X23211Y293680D01*
X23183Y293666D01*
X23135Y293618D01*
X23121Y293590D01*
X23072Y293542D01*
X23003Y293500D01*
X22933Y293431D01*
X22878Y293417D01*
X22788Y293382D01*
X22698Y293292D01*
X22601Y293237D01*
X22545Y293181D01*
X22476Y293153D01*
X22427Y293146D01*
X22420Y293140D01*
X22295Y293126D01*
X22115Y293043D01*
X22004Y293015D01*
X21810Y293001D01*
X21741Y292973D01*
X21651Y292938D01*
X21574Y292918D01*
X21519Y292904D01*
X21422Y292890D01*
X21366Y292876D01*
X21186Y292890D01*
X21144Y292904D01*
X21054Y292925D01*
X20985Y292952D01*
X20826Y293001D01*
X20687Y293015D01*
X20576Y293029D01*
X20340Y293140D01*
X20250Y293174D01*
X20229Y293195D01*
X20201Y293209D01*
X20118Y293264D01*
X20042Y293285D01*
X19993Y293306D01*
X19917Y293368D01*
X19883Y293403D01*
X19855Y293417D01*
X19792Y293479D01*
X19778Y293507D01*
X19744Y293542D01*
X19716Y293556D01*
X19668Y293604D01*
X19654Y293632D01*
X19619Y293666D01*
X19591Y293680D01*
X19529Y293743D01*
X19515Y293771D01*
X19480Y293805D01*
X19453Y293819D01*
X19404Y293868D01*
X19390Y293895D01*
X19307Y293979D01*
X19293Y294006D01*
X19265Y294076D01*
X19252Y294131D01*
X19154Y294270D01*
X19134Y294346D01*
X19106Y294415D01*
X19044Y294533D01*
X19016Y294630D01*
X18967Y294928D01*
X18946Y294977D01*
X18919Y295046D01*
X18905Y295102D01*
X18891Y295199D01*
X18877Y295338D01*
X18891Y295657D01*
X18905Y295698D01*
X18919Y295795D01*
X18988Y295948D01*
X19002Y296128D01*
X19037Y296274D01*
X19113Y296419D01*
X19147Y296509D01*
X19175Y296579D01*
X19210Y296614D01*
X19224Y296641D01*
X19265Y296738D01*
X19300Y296828D01*
X19390Y296919D01*
X19404Y296946D01*
X19605Y297147D01*
X19633Y297161D01*
X19654Y297182D01*
X19668Y297210D01*
X19883Y297425D01*
X19910Y297439D01*
X19980Y297508D01*
X20049Y297536D01*
X20139Y297570D01*
X20285Y297647D01*
X20396Y297674D01*
X20500Y297695D01*
X20617Y297744D01*
X20673Y297757D01*
X20812Y297771D01*
X20992Y297785D01*
X21297Y297799D01*
X21907Y297785D01*
D02*
G37*
G36*
X21588Y289797D02*
X21734Y289777D01*
X21789Y289763D01*
X21866Y289728D01*
X21963Y289700D01*
X22122Y289680D01*
X22205Y289666D01*
X22261Y289652D01*
X22406Y289576D01*
X22538Y289527D01*
X22615Y289478D01*
X22642Y289451D01*
X22816Y289388D01*
X22906Y289298D01*
X22933Y289284D01*
X22968Y289263D01*
X22982Y289236D01*
X23273Y288944D01*
X23287Y288917D01*
X23370Y288834D01*
X23419Y288702D01*
X23488Y288591D01*
X23523Y288515D01*
X23558Y288424D01*
X23627Y288314D01*
X23675Y288196D01*
X23710Y288106D01*
X23745Y288029D01*
X23759Y287932D01*
X23786Y287558D01*
X23800Y287267D01*
X23786Y287225D01*
X23765Y286816D01*
X23738Y286649D01*
X23689Y286532D01*
X23661Y286421D01*
X23648Y286324D01*
X23592Y286226D01*
X23537Y286102D01*
X23502Y286012D01*
X23412Y285921D01*
X23398Y285894D01*
X23336Y285817D01*
X23301Y285783D01*
X23259Y285686D01*
X23245Y285630D01*
X23183Y285554D01*
X23155Y285540D01*
X23121Y285505D01*
X23107Y285478D01*
X23086Y285457D01*
X23017Y285429D01*
X22926Y285394D01*
X22878Y285360D01*
X22809Y285290D01*
X22781Y285277D01*
X22705Y285214D01*
X22670Y285179D01*
X22497Y285117D01*
X22476Y285096D01*
X22351Y285041D01*
X22295Y285027D01*
X22178Y285006D01*
X22108Y284978D01*
X22018Y284944D01*
X21879Y284930D01*
X21824Y284916D01*
X21443Y284895D01*
X21242Y284888D01*
X21200Y284902D01*
X20826Y284916D01*
X20784Y284930D01*
X20645Y284944D01*
X20493Y285013D01*
X20403Y285048D01*
X20326Y285096D01*
X20174Y285166D01*
X20049Y285235D01*
X19924Y285290D01*
X19827Y285346D01*
X19772Y285401D01*
X19744Y285415D01*
X19668Y285478D01*
X19654Y285505D01*
X19591Y285568D01*
X19564Y285582D01*
X19543Y285602D01*
X19529Y285630D01*
X19467Y285693D01*
X19439Y285706D01*
X19404Y285741D01*
X19390Y285769D01*
X19328Y285845D01*
X19293Y285880D01*
X19265Y285949D01*
X19252Y286005D01*
X19196Y286102D01*
X19141Y286226D01*
X19113Y286393D01*
X19016Y286601D01*
X19002Y286698D01*
X18974Y286809D01*
X18919Y286934D01*
X18905Y286989D01*
X18891Y287086D01*
X18863Y287391D01*
X18877Y287433D01*
X18898Y287689D01*
X18912Y287759D01*
X18960Y287877D01*
X18988Y287946D01*
X19002Y288043D01*
X19023Y288133D01*
X19127Y288334D01*
X19161Y288424D01*
X19210Y288501D01*
X19265Y288626D01*
X19321Y288723D01*
X19362Y288764D01*
X19376Y288792D01*
X19404Y288820D01*
X19418Y288848D01*
X19439Y288868D01*
X19467Y288882D01*
X19543Y288958D01*
X19557Y288986D01*
X19577Y289007D01*
X19605Y289021D01*
X19681Y289097D01*
X19695Y289125D01*
X19716Y289146D01*
X19744Y289160D01*
X19806Y289222D01*
X19820Y289250D01*
X19855Y289284D01*
X19883Y289298D01*
X19959Y289361D01*
X19993Y289395D01*
X20063Y289423D01*
X20118Y289437D01*
X20271Y289534D01*
X20403Y289583D01*
X20465Y289617D01*
X20479D01*
X20604Y289673D01*
X20742Y289687D01*
X20867Y289700D01*
X20964Y289742D01*
X21034Y289770D01*
X21089Y289783D01*
X21249Y289804D01*
X21547Y289811D01*
X21588Y289797D01*
D02*
G37*
G36*
X126173Y291649D02*
X126228Y291635D01*
X126298Y291621D01*
X126388Y291586D01*
X126499Y291559D01*
X126672Y291538D01*
X126783Y291510D01*
X126852Y291482D01*
X126873Y291462D01*
X127012Y291420D01*
X127123Y291406D01*
X127331Y291309D01*
X127442Y291281D01*
X127553Y291267D01*
X127629Y291205D01*
X127663Y291170D01*
X127761Y291115D01*
X127830Y291045D01*
X127899Y291018D01*
X127920Y291011D01*
X127927Y291004D01*
X127983Y290990D01*
X128066Y290907D01*
X128093Y290893D01*
X128121Y290865D01*
X128149Y290851D01*
X128184Y290803D01*
X128246Y290740D01*
X128274Y290727D01*
X128343Y290657D01*
X128371Y290643D01*
X128440Y290616D01*
X128496Y290602D01*
X128572Y290539D01*
X128620Y290491D01*
X128648Y290477D01*
X128724Y290401D01*
X128738Y290373D01*
X128759Y290352D01*
X128787Y290338D01*
X128849Y290276D01*
X128863Y290248D01*
X128933Y290179D01*
X128946Y290151D01*
X128974Y290082D01*
X128988Y290026D01*
X129016Y289998D01*
X129030Y289971D01*
X129099Y289901D01*
X129113Y289874D01*
X129175Y289797D01*
X129210Y289763D01*
X129258Y289631D01*
X129293Y289583D01*
X129335Y289541D01*
X129348Y289513D01*
X129446Y289388D01*
X129473Y289361D01*
X129501Y289250D01*
X129515Y289139D01*
X129612Y288931D01*
X129640Y288820D01*
X129654Y288723D01*
X129737Y288542D01*
X129758Y288466D01*
X129771Y288314D01*
X129785Y288230D01*
X129806Y288154D01*
X129834Y288085D01*
X129862Y287988D01*
X129875Y287849D01*
X129903Y287474D01*
X129882Y287204D01*
X129868Y287038D01*
X129855Y286954D01*
X129813Y286843D01*
X129799Y286788D01*
X129778Y286712D01*
X129764Y286573D01*
X129751Y286476D01*
X129737Y286434D01*
X129668Y286282D01*
X129640Y286185D01*
X129626Y286074D01*
X129487Y285783D01*
X129432Y285686D01*
X129348Y285505D01*
X129293Y285408D01*
X129238Y285283D01*
X129182Y285186D01*
X129127Y285131D01*
X129113Y285103D01*
X129064Y285041D01*
X129037Y285027D01*
X128946Y284937D01*
X128939Y284916D01*
X128912Y284902D01*
X128821Y284812D01*
X128808Y284784D01*
X128724Y284715D01*
X128281Y284271D01*
X128274Y284250D01*
X128246Y284236D01*
X128156Y284146D01*
X128142Y284118D01*
X128093Y284084D01*
X128017Y284021D01*
X127983Y283987D01*
X127913Y283959D01*
X127858Y283945D01*
X127788Y283904D01*
X127761Y283876D01*
X127663Y283834D01*
X127573Y283800D01*
X127497Y283751D01*
X127345Y283682D01*
X127137Y283585D01*
X127081Y283571D01*
X126901Y283557D01*
X126845Y283543D01*
X126714Y283494D01*
X126596Y283460D01*
X126540Y283446D01*
X126402Y283432D01*
X126305Y283418D01*
X126173Y283397D01*
X126117Y283384D01*
X126006Y283342D01*
X125937Y283328D01*
X125826Y283314D01*
X125639Y283293D01*
X125452Y283314D01*
X125341Y283328D01*
X125271Y283342D01*
X125195Y283377D01*
X125119Y283397D01*
X125036Y283411D01*
X124848Y283432D01*
X124703Y283453D01*
X124647Y283467D01*
X124557Y283501D01*
X124460Y283543D01*
X124363Y283557D01*
X124307Y283571D01*
X124217Y283605D01*
X124044Y283682D01*
X123947Y283696D01*
X123864Y283709D01*
X123787Y283772D01*
X123753Y283806D01*
X123656Y283862D01*
X123586Y283931D01*
X123517Y283959D01*
X123427Y283994D01*
X123344Y284049D01*
X123267Y284084D01*
X123156Y284125D01*
X123073Y284209D01*
X123046Y284223D01*
X122955Y284313D01*
X122949Y284333D01*
X122921Y284347D01*
X122366Y284902D01*
X122338Y284916D01*
X122283Y284999D01*
X122206Y285075D01*
X122179Y285145D01*
X122137Y285256D01*
X122109Y285283D01*
X122096Y285311D01*
X122054Y285408D01*
X122019Y285498D01*
X121929Y285588D01*
X121915Y285616D01*
X121846Y285713D01*
X121818Y285741D01*
X121791Y285810D01*
X121777Y285907D01*
X121756Y285984D01*
X121728Y286053D01*
X121652Y286226D01*
X121631Y286358D01*
X121589Y286469D01*
X121569Y286545D01*
X121555Y286601D01*
X121534Y286927D01*
X121520Y287287D01*
X121513Y287683D01*
X121527Y287724D01*
X121541Y288223D01*
X121555Y288265D01*
X121569Y288459D01*
X121610Y288556D01*
X121638Y288653D01*
X121659Y288771D01*
X121686Y288841D01*
X121763Y289000D01*
X121777Y289097D01*
X121797Y289187D01*
X121825Y289256D01*
X121860Y289291D01*
X121902Y289388D01*
X121915Y289444D01*
X121957Y289513D01*
X122026Y289583D01*
X122040Y289610D01*
X122102Y289700D01*
X122123Y289707D01*
X122137Y289735D01*
X122179Y289832D01*
X122234Y289929D01*
X122304Y289998D01*
X122317Y290026D01*
X122935Y290643D01*
X122955Y290650D01*
X122969Y290678D01*
X123059Y290768D01*
X123087Y290782D01*
X123156Y290851D01*
X123226Y290879D01*
X123316Y290914D01*
X123378Y290976D01*
X123406Y290990D01*
X123434Y291018D01*
X123503Y291059D01*
X123573Y291129D01*
X123725Y291184D01*
X123822Y291254D01*
X123954Y291302D01*
X124002Y291323D01*
X124113Y291392D01*
X124280Y291420D01*
X124411Y291469D01*
X124488Y291503D01*
X124599Y291531D01*
X124779Y291545D01*
X124834Y291559D01*
X124973Y291572D01*
X125015Y291586D01*
X125154Y291628D01*
X125209Y291642D01*
X125348Y291656D01*
X125722Y291683D01*
X126173Y291649D01*
D02*
G37*
G36*
X21519Y281685D02*
X21803Y281664D01*
X21872Y281650D01*
X21983Y281608D01*
X22101Y281574D01*
X22157Y281560D01*
X22240Y281546D01*
X22337Y281490D01*
X22462Y281435D01*
X22531Y281407D01*
X22559Y281394D01*
X22656Y281324D01*
X22712Y281310D01*
X22802Y281276D01*
X22878Y281199D01*
X22906Y281185D01*
X22933Y281158D01*
X22961Y281144D01*
X23010Y281095D01*
X23024Y281068D01*
X23058Y281033D01*
X23086Y281019D01*
X23135Y280970D01*
X23148Y280943D01*
X23197Y280894D01*
X23225Y280880D01*
X23259Y280846D01*
X23273Y280818D01*
X23301Y280790D01*
X23315Y280763D01*
X23370Y280707D01*
X23398Y280638D01*
X23412Y280582D01*
X23474Y280506D01*
X23523Y280457D01*
X23578Y280360D01*
X23634Y280305D01*
X23661Y280208D01*
X23675Y280083D01*
X23731Y279958D01*
X23745Y279903D01*
X23759Y279806D01*
X23772Y279667D01*
X23786Y279403D01*
X23800Y279182D01*
X23786Y279043D01*
X23765Y278717D01*
X23752Y278592D01*
X23738Y278537D01*
X23710Y278467D01*
X23675Y278377D01*
X23661Y278322D01*
Y278308D01*
X23648Y278197D01*
X23585Y278121D01*
X23481Y277975D01*
X23440Y277934D01*
X23426Y277906D01*
X23370Y277767D01*
X23308Y277691D01*
X23273Y277656D01*
X23259Y277628D01*
X23197Y277566D01*
X23169Y277552D01*
X23135Y277517D01*
X23121Y277490D01*
X23058Y277427D01*
X23031Y277413D01*
X22996Y277379D01*
X22982Y277351D01*
X22933Y277302D01*
X22906Y277289D01*
X22822Y277205D01*
X22753Y277178D01*
X22663Y277143D01*
X22580Y277074D01*
X22545Y277039D01*
X22448Y276984D01*
X22393Y276928D01*
X22226Y276900D01*
X22094Y276852D01*
X22032Y276831D01*
X21977Y276817D01*
X21879Y276803D01*
X21616Y276789D01*
X21519Y276775D01*
X21006Y276789D01*
X20964Y276803D01*
X20784Y276817D01*
X20687Y276859D01*
X20617Y276886D01*
X20562Y276900D01*
X20444Y276921D01*
X20375Y276949D01*
X20271Y277011D01*
X20139Y277060D01*
X20090Y277094D01*
X20035Y277150D01*
X20007Y277164D01*
X19931Y277226D01*
X19883Y277275D01*
X19709Y277337D01*
X19681Y277365D01*
X19668Y277393D01*
X19584Y277448D01*
X19529Y277504D01*
X19515Y277531D01*
X19432Y277614D01*
X19404Y277684D01*
X19383Y277760D01*
X19362Y277781D01*
X19349Y277809D01*
X19279Y277878D01*
X19265Y277906D01*
X19203Y277982D01*
X19154Y278030D01*
X19092Y278204D01*
X19030Y278308D01*
X19016Y278405D01*
X19002Y278460D01*
X18981Y278634D01*
X18967Y278689D01*
X18933Y278766D01*
X18905Y278863D01*
X18891Y278960D01*
X18877Y279098D01*
X18891Y279417D01*
X18905Y279459D01*
X18919Y279542D01*
X18974Y279667D01*
X18988Y279722D01*
X19002Y279861D01*
X19023Y279993D01*
X19057Y280083D01*
X19113Y280208D01*
X19127Y280263D01*
X19141Y280360D01*
X19154Y280416D01*
X19217Y280492D01*
X19238Y280513D01*
X19252Y280541D01*
X19314Y280617D01*
X19355Y280658D01*
X19376Y280665D01*
X19390Y280693D01*
X19480Y280783D01*
X19508Y280797D01*
X19577Y280880D01*
X19619Y280922D01*
X19640Y280929D01*
X19654Y280957D01*
X19744Y281047D01*
X19772Y281061D01*
X19806Y281109D01*
X19869Y281172D01*
X19896Y281185D01*
X19980Y281269D01*
X20049Y281296D01*
X20139Y281331D01*
X20188Y281366D01*
X20243Y281421D01*
X20271Y281435D01*
X20347Y281497D01*
X20451Y281560D01*
X20590Y281574D01*
X20631Y281588D01*
X20728Y281629D01*
X20826Y281657D01*
X20923Y281671D01*
X21179Y281692D01*
X21477Y281699D01*
X21519Y281685D01*
D02*
G37*
G36*
X21491Y273572D02*
X21817Y273551D01*
X21956Y273537D01*
X22025Y273524D01*
X22094Y273496D01*
X22185Y273461D01*
X22282Y273447D01*
X22337Y273433D01*
X22427Y273399D01*
X22510Y273343D01*
X22663Y273288D01*
X22712Y273253D01*
X22781Y273184D01*
X22809Y273170D01*
X23010Y272969D01*
X23024Y272941D01*
X23072Y272906D01*
X23148Y272830D01*
X23162Y272802D01*
X23211Y272768D01*
X23412Y272567D01*
X23426Y272539D01*
X23495Y272470D01*
X23509Y272442D01*
X23537Y272372D01*
X23571Y272282D01*
X23634Y272178D01*
X23661Y272067D01*
X23682Y271950D01*
X23710Y271880D01*
X23745Y271790D01*
X23759Y271693D01*
X23772Y271513D01*
X23786Y271374D01*
X23800Y271027D01*
X23786Y270986D01*
X23772Y270597D01*
X23759Y270556D01*
X23745Y270417D01*
X23689Y270292D01*
X23661Y270181D01*
X23648Y270084D01*
X23592Y269987D01*
X23537Y269862D01*
X23502Y269772D01*
X23412Y269682D01*
X23398Y269654D01*
X23349Y269592D01*
X23322Y269578D01*
X23121Y269377D01*
X23107Y269349D01*
X23086Y269328D01*
X23058Y269315D01*
X22996Y269252D01*
X22982Y269224D01*
X22947Y269190D01*
X22920Y269176D01*
X22843Y269114D01*
X22809Y269079D01*
X22739Y269051D01*
X22649Y269016D01*
X22601Y268982D01*
X22420Y268899D01*
X22185Y268788D01*
X22060Y268774D01*
X22018Y268760D01*
X21921Y268718D01*
X21824Y268690D01*
X21727Y268677D01*
X21456Y268656D01*
X21228Y268649D01*
X21186Y268663D01*
X20874Y268684D01*
X20805Y268697D01*
X20694Y268739D01*
X20576Y268774D01*
X20520Y268788D01*
X20416Y268808D01*
X20243Y268899D01*
X20153Y268933D01*
X20104Y268954D01*
X20070Y268989D01*
X20063Y269009D01*
X20035Y269023D01*
X20007Y269051D01*
X19980Y269065D01*
X19917Y269127D01*
X19903Y269155D01*
X19883Y269176D01*
X19855Y269190D01*
X19792Y269252D01*
X19778Y269280D01*
X19744Y269315D01*
X19716Y269328D01*
X19668Y269377D01*
X19654Y269405D01*
X19619Y269439D01*
X19591Y269453D01*
X19529Y269516D01*
X19515Y269543D01*
X19480Y269578D01*
X19453Y269592D01*
X19404Y269641D01*
X19390Y269668D01*
X19307Y269751D01*
X19293Y269779D01*
X19265Y269848D01*
X19231Y269939D01*
X19210Y269959D01*
X19196Y269987D01*
X19168Y270015D01*
X19120Y270147D01*
X19092Y270216D01*
X19030Y270320D01*
X19002Y270417D01*
X18981Y270549D01*
X18905Y270736D01*
X18863Y271152D01*
X18877Y271194D01*
X18898Y271450D01*
X18912Y271506D01*
X18953Y271617D01*
X18988Y271707D01*
X19009Y271838D01*
X19023Y271894D01*
X19127Y272095D01*
X19161Y272185D01*
X19210Y272262D01*
X19279Y272414D01*
X19349Y272539D01*
X19404Y272664D01*
X19460Y272761D01*
X19515Y272816D01*
X19529Y272844D01*
X19564Y272892D01*
X19591Y272906D01*
X19619Y272934D01*
X19647Y272948D01*
X19702Y273031D01*
X19730Y273045D01*
X19806Y273107D01*
X19855Y273156D01*
X20028Y273218D01*
X20063Y273253D01*
X20090Y273267D01*
X20097Y273274D01*
X20104Y273281D01*
X20236Y273329D01*
X20306Y273357D01*
X20389Y273412D01*
X20465Y273433D01*
X20562Y273447D01*
X20694Y273496D01*
X20812Y273530D01*
X20867Y273544D01*
X21165Y273565D01*
X21332Y273579D01*
X21450Y273586D01*
X21491Y273572D01*
D02*
G37*
%LPC*%
G36*
X55634Y317505D02*
X55592Y317491D01*
X55218Y317478D01*
X55176Y317464D01*
X54857Y317450D01*
X54816Y317436D01*
X54760Y317422D01*
X54580Y317408D01*
X54524Y317395D01*
X54226Y317374D01*
X54178Y317367D01*
X54136Y317381D01*
X54081Y317367D01*
X53713Y317346D01*
X53519Y317332D01*
X53436Y317318D01*
X53366Y317304D01*
X53311Y317290D01*
X53124Y317270D01*
X53068Y317256D01*
X52770Y317221D01*
X52576Y317207D01*
X52507Y317193D01*
X52451Y317180D01*
X52375Y317159D01*
X52319Y317145D01*
X52028Y317103D01*
X51848Y317089D01*
X51806Y317076D01*
X51675Y317055D01*
X51619Y317041D01*
X51501Y317006D01*
X51356Y316985D01*
X51168Y316964D01*
X50933Y316937D01*
X50856Y316916D01*
X50697Y316854D01*
X50641Y316840D01*
X50496Y316805D01*
X50420Y316770D01*
X50350Y316743D01*
X50260Y316722D01*
X50191Y316708D01*
X50024Y316680D01*
X49969Y316666D01*
X49858Y316625D01*
X49768Y316590D01*
X49629Y316576D01*
X49532Y316562D01*
X49476Y316549D01*
X49386Y316514D01*
X49317Y316486D01*
X49227Y316451D01*
X49172Y316438D01*
X49067Y316417D01*
X48998Y316389D01*
X48922Y316354D01*
X48853Y316327D01*
X48797Y316313D01*
X48651Y316278D01*
X48582Y316250D01*
X48436Y316188D01*
X48381Y316174D01*
X48277Y316153D01*
X48138Y316098D01*
X48062Y316063D01*
X47965Y316035D01*
X47847Y316015D01*
X47702Y315938D01*
X47604Y315897D01*
X47369Y315786D01*
X47272Y315772D01*
X47195Y315751D01*
X46911Y315619D01*
X46814Y315564D01*
X46661Y315494D01*
X46537Y315425D01*
X46384Y315356D01*
X46148Y315245D01*
X46017Y315224D01*
X45947Y315196D01*
X45829Y315134D01*
X45760Y315106D01*
X45302Y314870D01*
X45164Y314815D01*
X45087Y314753D01*
X45053Y314718D01*
X45025Y314704D01*
X44858Y314593D01*
X44803Y314579D01*
X44671Y314559D01*
X44595Y314510D01*
X44553Y314468D01*
X44456Y314413D01*
X44401Y314357D01*
X44373Y314343D01*
X44248Y314288D01*
X44124Y314219D01*
X43999Y314163D01*
X43929Y314122D01*
X43874Y314066D01*
X43846Y314052D01*
X43818Y314025D01*
X43791Y314011D01*
X43749Y313969D01*
X43721Y313955D01*
X43694Y313927D01*
X43638Y313914D01*
X43513Y313844D01*
X43458Y313789D01*
X43430Y313775D01*
X43389Y313733D01*
X43361Y313720D01*
X43319Y313678D01*
X43292Y313664D01*
X43222Y313636D01*
X43167Y313622D01*
X43084Y313539D01*
X43056Y313525D01*
X42931Y313428D01*
X42903Y313400D01*
X42834Y313373D01*
X42778Y313359D01*
X42702Y313297D01*
X42667Y313262D01*
X42640Y313248D01*
X42459Y313068D01*
X42432Y313054D01*
X42390Y313012D01*
X42321Y312985D01*
X42231Y312950D01*
X42196Y312915D01*
X42168Y312901D01*
X42113Y312846D01*
X42085Y312832D01*
X42043Y312790D01*
X42016Y312777D01*
X41974Y312735D01*
X41821Y312679D01*
X41738Y312596D01*
X41711Y312582D01*
X41634Y312520D01*
X41620Y312492D01*
X41558Y312430D01*
X41530Y312416D01*
X41496Y312367D01*
X41419Y312291D01*
X41392Y312277D01*
X41336Y312222D01*
X41308Y312208D01*
X41239Y312180D01*
X41149Y312146D01*
X41059Y312055D01*
X41031Y312041D01*
X40996Y312021D01*
X40982Y311993D01*
X40566Y311577D01*
X40553Y311549D01*
X40518Y311514D01*
X40490Y311501D01*
X40414Y311438D01*
X40379Y311404D01*
X40227Y311348D01*
X40171Y311293D01*
X40143Y311279D01*
X40116Y311251D01*
X40088Y311237D01*
X40040Y311189D01*
X40026Y311161D01*
X39977Y311112D01*
X39949Y311098D01*
X39901Y311050D01*
X39887Y311022D01*
X39852Y310987D01*
X39825Y310974D01*
X39762Y310911D01*
X39748Y310884D01*
X39714Y310849D01*
X39686Y310835D01*
X39637Y310786D01*
X39623Y310759D01*
X39589Y310724D01*
X39561Y310710D01*
X39499Y310648D01*
X39485Y310620D01*
X39450Y310585D01*
X39422Y310571D01*
X39374Y310523D01*
X39360Y310495D01*
X39325Y310460D01*
X39297Y310447D01*
X39235Y310384D01*
X39221Y310357D01*
X39187Y310322D01*
X39159Y310308D01*
X39096Y310246D01*
X39083Y310218D01*
X39055Y310190D01*
X39041Y310162D01*
X38999Y310121D01*
X38951Y309989D01*
X38916Y309940D01*
X38861Y309885D01*
X38847Y309857D01*
X38812Y309809D01*
X38784Y309795D01*
X38680Y309691D01*
X38674Y309670D01*
X38646Y309656D01*
X38403Y309414D01*
X38389Y309386D01*
X38361Y309316D01*
X38396Y309268D01*
X38493Y309254D01*
X38604Y309268D01*
X38680Y309330D01*
X38701Y309351D01*
X38798Y309407D01*
X38833Y309441D01*
X38847Y309469D01*
X38909Y309531D01*
X38937Y309545D01*
X38972Y309580D01*
X38986Y309608D01*
X39048Y309684D01*
X39083Y309719D01*
X39103Y309795D01*
X39131Y309864D01*
X39207Y309940D01*
X39221Y309968D01*
X39284Y310044D01*
X39311Y310058D01*
X39388Y310135D01*
X39402Y310162D01*
X39450Y310197D01*
X39526Y310273D01*
X39533Y310294D01*
X39561Y310308D01*
X39651Y310398D01*
X39665Y310426D01*
X39686Y310447D01*
X39714Y310460D01*
X39776Y310523D01*
X39790Y310551D01*
X39811Y310571D01*
X39838Y310585D01*
X39915Y310662D01*
X39929Y310689D01*
X39949Y310710D01*
X39977Y310724D01*
X40053Y310800D01*
X40060Y310821D01*
X40088Y310835D01*
X40192Y310939D01*
X40199Y310960D01*
X40227Y310974D01*
X40317Y311064D01*
X40331Y311091D01*
X40352Y311112D01*
X40379Y311126D01*
X40407Y311154D01*
X40435Y311168D01*
X40490Y311223D01*
X40560Y311251D01*
X40650Y311286D01*
X40712Y311348D01*
X40740Y311362D01*
X40767Y311390D01*
X40795Y311404D01*
X40830Y311438D01*
X40844Y311466D01*
X40892Y311514D01*
X40920Y311528D01*
X40969Y311577D01*
X40982Y311605D01*
X41031Y311653D01*
X41059Y311667D01*
X41093Y311702D01*
X41107Y311729D01*
X41170Y311792D01*
X41197Y311806D01*
X41232Y311840D01*
X41246Y311868D01*
X41308Y311931D01*
X41329Y311938D01*
X41336Y311958D01*
X41357Y311965D01*
X41371Y311993D01*
X41447Y312069D01*
X41475Y312083D01*
X41530Y312139D01*
X41558Y312152D01*
X41697Y312208D01*
X41773Y312270D01*
X41808Y312305D01*
X41835Y312319D01*
X42154Y312638D01*
X42182Y312652D01*
X42210Y312679D01*
X42238Y312693D01*
X42307Y312721D01*
X42404Y312777D01*
X42432Y312804D01*
X42459Y312818D01*
X42501Y312860D01*
X42529Y312873D01*
X42570Y312915D01*
X42598Y312929D01*
X42626Y312957D01*
X42695Y312985D01*
X42751Y312998D01*
X42827Y313061D01*
X42862Y313095D01*
X42889Y313109D01*
X42917Y313137D01*
X42945Y313151D01*
X43000Y313206D01*
X43028Y313220D01*
X43167Y313276D01*
X43194Y313303D01*
X43222Y313317D01*
X43278Y313373D01*
X43305Y313387D01*
X43382Y313463D01*
X43396Y313491D01*
X43430Y313525D01*
X43458Y313539D01*
X43499Y313581D01*
X43527Y313595D01*
X43555Y313622D01*
X43624Y313650D01*
X43714Y313685D01*
X43798Y313740D01*
X43874Y313775D01*
X43964Y313810D01*
X44047Y313879D01*
X44082Y313914D01*
X44110Y313927D01*
X44186Y313990D01*
X44207Y314011D01*
X44304Y314052D01*
X44484Y314149D01*
X44581Y314191D01*
X44651Y314219D01*
X44748Y314288D01*
X44817Y314316D01*
X44872Y314330D01*
X44970Y314385D01*
X45122Y314454D01*
X45191Y314496D01*
X45247Y314552D01*
X45275Y314565D01*
X45302Y314593D01*
X45330Y314607D01*
X45385Y314662D01*
X45413Y314676D01*
X45538Y314732D01*
X45635Y314787D01*
X45815Y314870D01*
X46023Y314968D01*
X46079Y314981D01*
X46183Y315002D01*
X46252Y315030D01*
X46342Y315079D01*
X46481Y315134D01*
X46509Y315148D01*
X46620Y315217D01*
X46689Y315245D01*
X47369Y315578D01*
X47438Y315619D01*
X47493Y315633D01*
X47590Y315647D01*
X47646Y315661D01*
X47826Y315744D01*
X47923Y315772D01*
X48069Y315807D01*
X48222Y315876D01*
X48339Y315911D01*
X48443Y315931D01*
X48513Y315959D01*
X48658Y316021D01*
X48769Y316049D01*
X48859Y316070D01*
X49012Y316139D01*
X49130Y316174D01*
X49275Y316209D01*
X49352Y316243D01*
X49449Y316285D01*
X49560Y316313D01*
X49650Y316334D01*
X49719Y316361D01*
X49809Y316396D01*
X49920Y316424D01*
X50080Y316444D01*
X50343Y316486D01*
X50454Y316528D01*
X50531Y316549D01*
X50641Y316576D01*
X50815Y316597D01*
X50870Y316611D01*
X50940Y316639D01*
X51030Y316673D01*
X51141Y316701D01*
X51335Y316729D01*
X51390Y316743D01*
X51522Y316791D01*
X51591Y316805D01*
X51716Y316819D01*
X51785Y316833D01*
X51897Y316847D01*
X52035Y316861D01*
X52202Y316888D01*
X52271Y316902D01*
X52389Y316937D01*
X52659Y316958D01*
X52881Y316985D01*
X53075Y316999D01*
X53263Y317020D01*
X53373Y317048D01*
X53512Y317062D01*
X53692Y317076D01*
X54386Y317103D01*
X55086Y317110D01*
X56549Y317103D01*
X56591Y317117D01*
X57354Y317103D01*
X57915Y317082D01*
X58165Y317069D01*
X58359Y317055D01*
X58428Y317041D01*
X58539Y317013D01*
X58914Y316971D01*
X59135Y316944D01*
X59288Y316930D01*
X59351Y316909D01*
X59447Y316881D01*
X59559Y316854D01*
X59767Y316840D01*
X59808Y316826D01*
X59891Y316812D01*
X59933Y316798D01*
X60086Y316756D01*
X60182Y316729D01*
X60363Y316715D01*
X60460Y316701D01*
X60550Y316680D01*
X60606Y316666D01*
X60716Y316625D01*
X60793Y316604D01*
X60848Y316590D01*
X61021Y316569D01*
X61132Y316542D01*
X61202Y316514D01*
X61320Y316479D01*
X61375Y316465D01*
X61549Y316444D01*
X61632Y316431D01*
X61743Y316417D01*
X61798Y316403D01*
X61909Y316361D01*
X61999Y316327D01*
X62055Y316313D01*
X62159Y316292D01*
X62228Y316264D01*
X62374Y316202D01*
X62429Y316188D01*
X62533Y316167D01*
X62644Y316126D01*
X62790Y316063D01*
X62845Y316049D01*
X62949Y316028D01*
X63018Y316001D01*
X63206Y315924D01*
X63303Y315911D01*
X63435Y315862D01*
X63580Y315800D01*
X63636Y315786D01*
X63781Y315751D01*
X64065Y315619D01*
X64274Y315522D01*
X64405Y315501D01*
X64475Y315474D01*
X64592Y315411D01*
X64690Y315370D01*
X64925Y315259D01*
X64981Y315245D01*
X65092Y315231D01*
X65328Y315120D01*
X65480Y315037D01*
X65633Y314968D01*
X65660Y314954D01*
X65737Y314891D01*
X65785Y314857D01*
X65861Y314794D01*
X65896Y314760D01*
X65924Y314746D01*
X66021Y314704D01*
X66111Y314669D01*
X66194Y314614D01*
X66270Y314593D01*
X66326Y314579D01*
X66423Y314565D01*
X66659Y314454D01*
X66756Y314399D01*
X66832Y314337D01*
X66853Y314316D01*
X66881Y314302D01*
X66957Y314240D01*
X66992Y314205D01*
X67144Y314149D01*
X67227Y314094D01*
X67325Y314052D01*
X67449Y313983D01*
X67505Y313927D01*
X67533Y313914D01*
X67609Y313851D01*
X67643Y313817D01*
X67713Y313789D01*
X67803Y313754D01*
X67824Y313733D01*
X68004Y313650D01*
X68101Y313595D01*
X68129Y313567D01*
X68157Y313553D01*
X68337Y313373D01*
X68365Y313359D01*
X68448Y313276D01*
X68580Y313227D01*
X68628Y313193D01*
X68704Y313130D01*
X68787Y313075D01*
X68850Y313012D01*
X68919Y312985D01*
X68975Y312971D01*
X69100Y312873D01*
X69176Y312811D01*
X69197Y312790D01*
X69224Y312777D01*
X69266Y312735D01*
X69342Y312714D01*
X69453Y312645D01*
X69488Y312610D01*
X69516Y312596D01*
X69807Y312305D01*
X69835Y312291D01*
X69918Y312208D01*
X70015Y312180D01*
X70084Y312139D01*
X70160Y312076D01*
X70209Y312041D01*
X70271Y311979D01*
X70285Y311951D01*
X70320Y311917D01*
X70348Y311903D01*
X70382Y311868D01*
X70396Y311840D01*
X70459Y311778D01*
X70486Y311764D01*
X70563Y311702D01*
X70597Y311667D01*
X70687Y311646D01*
X70764Y311598D01*
X70805Y311556D01*
X70833Y311542D01*
X70861Y311514D01*
X70889Y311501D01*
X70909Y311480D01*
X70923Y311452D01*
X71166Y311209D01*
X71187Y311203D01*
X71200Y311175D01*
X71818Y310558D01*
X71838Y310551D01*
X71852Y310523D01*
X72345Y310031D01*
X72365Y310024D01*
X72379Y309996D01*
X72594Y309781D01*
X72622Y309767D01*
X72657Y309732D01*
X72670Y309705D01*
X72733Y309642D01*
X72761Y309628D01*
X72795Y309594D01*
X72809Y309566D01*
X72872Y309490D01*
X72892Y309469D01*
X72920Y309400D01*
X72955Y309310D01*
X73017Y309247D01*
X73031Y309219D01*
X73059Y309192D01*
X73073Y309164D01*
X73121Y309115D01*
X73149Y309102D01*
X73197Y309053D01*
X73211Y309025D01*
X73260Y308977D01*
X73288Y308963D01*
X73336Y308914D01*
X73350Y308887D01*
X73392Y308845D01*
X73405Y308817D01*
X73433Y308790D01*
X73482Y308658D01*
X73517Y308609D01*
X73572Y308554D01*
X73586Y308526D01*
X73877Y308235D01*
X73891Y308207D01*
X73946Y308151D01*
X73960Y308124D01*
X73988Y308055D01*
X74043Y307957D01*
X74106Y307881D01*
X74127Y307860D01*
X74141Y307833D01*
X74182Y307791D01*
X74196Y307763D01*
X74238Y307722D01*
X74258Y307645D01*
X74286Y307576D01*
X74362Y307500D01*
X74376Y307472D01*
X74473Y307347D01*
X74501Y307320D01*
X74515Y307264D01*
X74584Y307139D01*
X74640Y307084D01*
X74654Y307056D01*
X74758Y306952D01*
X74778Y306945D01*
X74792Y306917D01*
X74834Y306876D01*
X74848Y306848D01*
X74889Y306806D01*
X74917Y306737D01*
X74952Y306647D01*
X75007Y306564D01*
X75056Y306446D01*
X75111Y306349D01*
X75167Y306293D01*
X75181Y306266D01*
X75208Y306238D01*
X75222Y306210D01*
X75278Y306155D01*
X75292Y306127D01*
X75333Y306030D01*
X75416Y305877D01*
X75458Y305780D01*
X75514Y305683D01*
X75569Y305628D01*
X75583Y305600D01*
X75645Y305524D01*
X75680Y305475D01*
X75708Y305447D01*
X75742Y305357D01*
X75770Y305288D01*
X75832Y305184D01*
X75867Y305094D01*
X75888Y305045D01*
X75943Y304962D01*
X75985Y304865D01*
X76013Y304795D01*
X76082Y304685D01*
X76124Y304587D01*
X76359Y304130D01*
X76401Y304033D01*
X76436Y303943D01*
X76456Y303922D01*
X76498Y303825D01*
X76512Y303728D01*
X76526Y303672D01*
X76561Y303582D01*
X76623Y303478D01*
X76637Y303423D01*
X76900Y302882D01*
X76914Y302826D01*
X76928Y302715D01*
X77025Y302507D01*
X77053Y302396D01*
X77067Y302313D01*
X77122Y302188D01*
X77164Y302091D01*
X77192Y301980D01*
X77205Y301897D01*
X77275Y301745D01*
X77302Y301675D01*
X77316Y301620D01*
X77337Y301502D01*
X77406Y301349D01*
X77441Y301259D01*
X77455Y301204D01*
X77469Y301107D01*
X77538Y300954D01*
X77566Y300885D01*
X77601Y300725D01*
X77642Y300614D01*
X77677Y300524D01*
X77691Y300469D01*
X77712Y300309D01*
X77739Y300087D01*
X77767Y299976D01*
X77802Y299886D01*
X77843Y299748D01*
X77864Y299574D01*
X77878Y299505D01*
X77920Y299394D01*
X77961Y299241D01*
X77975Y299158D01*
X78003Y298909D01*
X78031Y298798D01*
X78065Y298680D01*
X78093Y298569D01*
X78107Y298472D01*
X78121Y298416D01*
X78134Y298222D01*
X78148Y298181D01*
X78204Y297986D01*
X78239Y297647D01*
X78252Y297536D01*
X78266Y297314D01*
X78287Y297127D01*
X78322Y296967D01*
X78342Y296780D01*
X78363Y296426D01*
X78377Y295899D01*
X78391Y295095D01*
X78426Y295046D01*
X78446Y295026D01*
X78502Y295012D01*
X78710Y295026D01*
X78759Y295074D01*
X78772Y295130D01*
X78759Y295310D01*
X78703Y295435D01*
X78689Y295532D01*
X78668Y295802D01*
X78654Y295955D01*
X78627Y296537D01*
X78613Y296773D01*
X78599Y296967D01*
X78585Y297078D01*
X78571Y297147D01*
X78558Y297203D01*
X78544Y297272D01*
X78516Y297439D01*
X78488Y297716D01*
X78460Y297882D01*
X78446Y297938D01*
X78426Y298000D01*
X78412Y298056D01*
X78398Y298194D01*
X78384Y298250D01*
X78356Y298527D01*
X78342Y298583D01*
X78329Y298694D01*
X78301Y298763D01*
X78259Y298929D01*
X78245Y299068D01*
X78232Y299123D01*
X78218Y299262D01*
X78204Y299304D01*
X78190Y299359D01*
X78148Y299498D01*
X78134Y299554D01*
X78107Y299748D01*
X78086Y299921D01*
X78072Y299976D01*
X78031Y300087D01*
X77996Y300177D01*
X77968Y300289D01*
X77954Y300372D01*
X77885Y300524D01*
X77857Y300621D01*
X77836Y300795D01*
X77822Y300864D01*
X77767Y301017D01*
X77732Y301107D01*
X77705Y301218D01*
X77684Y301294D01*
X77649Y301384D01*
X77607Y301481D01*
X77580Y301578D01*
X77545Y301724D01*
X77469Y301897D01*
X77441Y302008D01*
X77420Y302084D01*
X77379Y302195D01*
X77330Y302313D01*
X77302Y302424D01*
X77288Y302507D01*
X77219Y302618D01*
X77205Y302674D01*
X77053Y302993D01*
X77039Y303131D01*
X76900Y303423D01*
X76831Y303547D01*
X76762Y303700D01*
X76692Y303825D01*
X76623Y303977D01*
X76526Y304185D01*
X76505Y304317D01*
X76477Y304386D01*
X76297Y304747D01*
X76165Y305017D01*
X76040Y305253D01*
X75985Y305309D01*
X75971Y305336D01*
X75909Y305413D01*
X75860Y305503D01*
X75846Y305600D01*
X75832Y305683D01*
X75791Y305752D01*
X75749Y305794D01*
X75735Y305822D01*
X75638Y305947D01*
X75583Y306030D01*
X75562Y306106D01*
X75493Y306217D01*
X75458Y306293D01*
X75423Y306383D01*
X75354Y306467D01*
X75333Y306487D01*
X75319Y306515D01*
X75257Y306591D01*
X75222Y306626D01*
X75208Y306654D01*
X75181Y306723D01*
X75111Y306848D01*
X75042Y306917D01*
X75028Y306945D01*
X74987Y306987D01*
X74973Y307014D01*
X74945Y307042D01*
X74917Y307111D01*
X74882Y307202D01*
X74806Y307278D01*
X74792Y307306D01*
X74730Y307382D01*
X74695Y307416D01*
X74654Y307500D01*
Y307514D01*
X74584Y307638D01*
X74529Y307694D01*
X74515Y307722D01*
X74335Y307902D01*
X74321Y307930D01*
X74279Y307971D01*
X74251Y308041D01*
X74217Y308131D01*
X74154Y308193D01*
X74141Y308221D01*
X74099Y308263D01*
X74085Y308290D01*
X74036Y308325D01*
X73974Y308387D01*
X73960Y308415D01*
X73919Y308457D01*
X73905Y308484D01*
X73877Y308512D01*
X73849Y308581D01*
X73815Y308672D01*
X73738Y308748D01*
X73724Y308776D01*
X73558Y308942D01*
X73544Y308970D01*
X73489Y309025D01*
X73475Y309053D01*
X73447Y309122D01*
X73433Y309178D01*
X73371Y309254D01*
X73336Y309289D01*
X73322Y309316D01*
X73232Y309407D01*
X73204Y309420D01*
X73170Y309469D01*
X72996Y309642D01*
X72969Y309656D01*
X72934Y309691D01*
X72920Y309719D01*
X72858Y309781D01*
X72830Y309795D01*
X72795Y309830D01*
X72782Y309857D01*
X72740Y309899D01*
X72726Y309927D01*
X72670Y309982D01*
X72643Y310079D01*
X72601Y310149D01*
X72546Y310204D01*
X72532Y310232D01*
X72470Y310308D01*
X72393Y310370D01*
X72379Y310398D01*
X72331Y310447D01*
X72303Y310460D01*
X72255Y310509D01*
X72241Y310537D01*
X72192Y310585D01*
X72164Y310599D01*
X72130Y310634D01*
X72116Y310662D01*
X72067Y310710D01*
X72040Y310724D01*
X71991Y310773D01*
X71977Y310800D01*
X71929Y310849D01*
X71901Y310863D01*
X71852Y310911D01*
X71838Y310939D01*
X71790Y310987D01*
X71762Y311001D01*
X71727Y311036D01*
X71714Y311064D01*
X71665Y311112D01*
X71637Y311126D01*
X71561Y311189D01*
X71526Y311223D01*
X71374Y311279D01*
X71318Y311334D01*
X71291Y311348D01*
X71263Y311376D01*
X71235Y311390D01*
X71187Y311438D01*
X71173Y311466D01*
X71138Y311501D01*
X71110Y311514D01*
X71062Y311563D01*
X71048Y311591D01*
X70999Y311639D01*
X70972Y311653D01*
X70909Y311716D01*
X70896Y311743D01*
X70722Y311917D01*
X70694Y311931D01*
X70674Y311951D01*
X70660Y311979D01*
X70583Y312055D01*
X70556Y312069D01*
X70486Y312139D01*
X70459Y312152D01*
X70389Y312180D01*
X70334Y312194D01*
X70258Y312256D01*
X70223Y312291D01*
X70195Y312305D01*
X70029Y312471D01*
X70001Y312485D01*
X69932Y312555D01*
X69876Y312568D01*
X69786Y312603D01*
X69724Y312666D01*
X69696Y312679D01*
X69668Y312707D01*
X69640Y312721D01*
X69564Y312797D01*
X69550Y312825D01*
X69502Y312860D01*
X69460Y312901D01*
X69432Y312915D01*
X69405Y312943D01*
X69377Y312957D01*
X69308Y312985D01*
X69211Y313040D01*
X69183Y313068D01*
X69155Y313081D01*
X68989Y313248D01*
X68961Y313262D01*
X68878Y313345D01*
X68808Y313373D01*
X68753Y313387D01*
X68503Y313581D01*
X68462Y313622D01*
X68406Y313636D01*
X68316Y313671D01*
X68281Y313706D01*
X68254Y313720D01*
X68198Y313775D01*
X68170Y313789D01*
X68101Y313858D01*
X68073Y313872D01*
X67976Y313914D01*
X67879Y313969D01*
X67824Y314025D01*
X67796Y314038D01*
X67768Y314066D01*
X67741Y314080D01*
X67671Y314149D01*
X67602Y314177D01*
X67512Y314212D01*
X67408Y314274D01*
X67338Y314302D01*
X67214Y314371D01*
X67172Y314413D01*
X67144Y314427D01*
X67068Y314489D01*
X67019Y314538D01*
X66950Y314565D01*
X66860Y314600D01*
X66777Y314656D01*
X66700Y314690D01*
X66603Y314732D01*
X66576Y314746D01*
X66492Y314801D01*
X66395Y314843D01*
X66305Y314877D01*
X66284Y314898D01*
X66257Y314912D01*
X66104Y314981D01*
X65979Y315051D01*
X65827Y315120D01*
X65591Y315231D01*
X65535Y315245D01*
X65425Y315259D01*
X65328Y315314D01*
X65230Y315356D01*
X65140Y315391D01*
X65057Y315446D01*
X64814Y315564D01*
X64440Y315744D01*
X64343Y315772D01*
X64246Y315786D01*
X63955Y315924D01*
X63747Y316021D01*
X63650Y316035D01*
X63518Y316084D01*
X63448Y316112D01*
X63372Y316146D01*
X63317Y316160D01*
X63171Y316195D01*
X63102Y316223D01*
X63025Y316257D01*
X62956Y316285D01*
X62901Y316299D01*
X62797Y316320D01*
X62686Y316361D01*
X62609Y316396D01*
X62540Y316424D01*
X62443Y316438D01*
X62311Y316486D01*
X62221Y316521D01*
X62152Y316549D01*
X62055Y316562D01*
X61999Y316576D01*
X61847Y316590D01*
X61722Y316646D01*
X61652Y316673D01*
X61542Y316701D01*
X61458Y316715D01*
X61334Y316770D01*
X61264Y316798D01*
X61167Y316826D01*
X60994Y316847D01*
X60925Y316861D01*
X60813Y316902D01*
X60737Y316923D01*
X60682Y316937D01*
X60508Y316958D01*
X60356Y316971D01*
X60106Y317013D01*
X60051Y317027D01*
X59974Y317048D01*
X59919Y317062D01*
X59725Y317089D01*
X59538Y317110D01*
X59454Y317124D01*
X59344Y317138D01*
X59274Y317152D01*
X59219Y317166D01*
X59142Y317186D01*
X58976Y317214D01*
X58622Y317249D01*
X58435Y317270D01*
X58338Y317283D01*
X58262Y317304D01*
X58193Y317318D01*
X58005Y317339D01*
X57742Y317353D01*
X57561Y317367D01*
X57457Y317374D01*
X57395Y317367D01*
X57354Y317381D01*
X57069Y317401D01*
X56930Y317415D01*
X56778Y317443D01*
X56667Y317457D01*
X56417Y317471D01*
X56265Y317485D01*
X56001Y317498D01*
X55634Y317505D01*
D02*
G37*
G36*
X52444Y307784D02*
X44449Y307777D01*
X44290Y307784D01*
X44248Y307770D01*
X44110Y307756D01*
X43714Y307736D01*
X43666Y307715D01*
X43562Y307611D01*
X43548Y307555D01*
X43527Y307132D01*
X43506Y306945D01*
X43499Y295525D01*
X43513Y295358D01*
X43548Y295310D01*
X43569Y295289D01*
X43624Y295275D01*
X46356Y295289D01*
X46405Y295338D01*
X46419Y295393D01*
X46426Y296218D01*
X46419Y296267D01*
X46432Y296308D01*
X46419Y296447D01*
X46432Y296877D01*
X46426Y304802D01*
X46439Y304927D01*
X46467Y304969D01*
X46537Y304997D01*
X48755Y304983D01*
X48804Y304948D01*
X48818Y304893D01*
X48825Y304816D01*
X48818Y304740D01*
X48832Y304698D01*
X48825Y304026D01*
X48832Y303950D01*
X48818Y303908D01*
X48825Y303665D01*
X48818Y303520D01*
X48832Y303478D01*
X48825Y303277D01*
X48832Y296516D01*
Y296502D01*
X48846Y295934D01*
X48859Y295892D01*
X48873Y295490D01*
X48943Y295393D01*
X48977Y295358D01*
X49005Y295345D01*
X49074Y295317D01*
X49546Y295303D01*
X49587Y295289D01*
X49685Y295275D01*
X49893Y295289D01*
X49934Y295275D01*
X51404Y295289D01*
X51467Y295338D01*
X51480Y295393D01*
X51494Y304920D01*
X51543Y304983D01*
X51640Y304997D01*
X52195Y305010D01*
X52236Y305024D01*
X52347Y305038D01*
X52375Y305066D01*
X52403Y305080D01*
X52465Y305142D01*
X52479Y305170D01*
X52507Y305239D01*
X52527Y305704D01*
X52541Y305773D01*
X52548Y305947D01*
X52534Y305988D01*
X52548Y306127D01*
X52534Y307722D01*
X52514Y307756D01*
X52444Y307784D01*
D02*
G37*
G36*
X67311D02*
X67269Y307770D01*
X67130Y307784D01*
X61223Y307770D01*
X61181Y307756D01*
X60758Y307736D01*
X60647Y307694D01*
X60494Y307638D01*
X60446Y307604D01*
X60418Y307576D01*
X60391Y307562D01*
X60363Y307534D01*
X60335Y307521D01*
X60273Y307458D01*
X60259Y307430D01*
X60224Y307396D01*
X60196Y307382D01*
X60120Y307306D01*
X60106Y307278D01*
X60086Y307257D01*
X60058Y307243D01*
X59995Y307181D01*
X59981Y307153D01*
X59961Y307132D01*
X59933Y307118D01*
X59857Y307042D01*
X59843Y307014D01*
X59794Y306980D01*
X59732Y306917D01*
X59718Y306890D01*
X59697Y306869D01*
X59669Y306855D01*
X59607Y306793D01*
X59593Y306765D01*
X59559Y306730D01*
X59531Y306716D01*
X59454Y306640D01*
X59441Y306612D01*
X59420Y306591D01*
X59392Y306577D01*
X59330Y306515D01*
X59316Y306487D01*
X59295Y306467D01*
X59267Y306453D01*
X59205Y306390D01*
X59191Y306363D01*
X59156Y306328D01*
X59129Y306314D01*
X59066Y306252D01*
X59052Y306224D01*
X59032Y306203D01*
X59004Y306189D01*
X58941Y306127D01*
X58927Y306099D01*
X58844Y305974D01*
X58816Y305863D01*
X58803Y305683D01*
X58789Y305641D01*
X58775Y305586D01*
X58747Y305517D01*
X58733Y305461D01*
X58720Y305322D01*
X58699Y304969D01*
X58685Y304553D01*
X58678Y298375D01*
X58692Y298333D01*
X58706Y297764D01*
X58720Y297723D01*
X58733Y297446D01*
X58789Y297321D01*
X58810Y297231D01*
X58830Y297099D01*
X58900Y296988D01*
X58927Y296919D01*
X58969Y296808D01*
X59032Y296731D01*
X59066Y296697D01*
X59080Y296669D01*
X59156Y296593D01*
X59184Y296579D01*
X59253Y296509D01*
X59323Y296482D01*
X59413Y296447D01*
X59461Y296412D01*
X59496Y296364D01*
X59531Y296329D01*
X59559Y296315D01*
X59579Y296294D01*
X59607Y296225D01*
X59628Y296149D01*
X59649Y296128D01*
X59662Y296100D01*
X59697Y296066D01*
X59725Y296052D01*
X59760Y296003D01*
X59794Y295969D01*
X59968Y295906D01*
X59995Y295879D01*
X60009Y295851D01*
X60058Y295802D01*
X60086Y295788D01*
X60106Y295767D01*
X60134Y295698D01*
X60169Y295608D01*
X60203Y295560D01*
X60252Y295525D01*
X60273Y295504D01*
X60286Y295476D01*
X60321Y295442D01*
X60391Y295414D01*
X60522Y295365D01*
X60612Y295331D01*
X60793Y295317D01*
X61146Y295296D01*
X61729Y295282D01*
X65633Y295275D01*
X65647D01*
X68198Y295289D01*
X68233Y295324D01*
X68261Y295435D01*
X68247Y297737D01*
X68198Y297785D01*
X68143Y297799D01*
X63268Y297806D01*
X63095Y297799D01*
X63053Y297813D01*
X62824Y297806D01*
X62665Y297813D01*
X62623Y297799D01*
X62491Y297820D01*
X62457Y297827D01*
X62415Y297813D01*
X62304Y297799D01*
X62263Y297813D01*
X62152Y297841D01*
X61791Y297855D01*
X61659Y297986D01*
X61646Y298042D01*
X61632Y298139D01*
X61618Y298458D01*
X61604Y298500D01*
X61618Y298735D01*
X61604Y298777D01*
X61611Y299657D01*
X61604Y299803D01*
X61618Y299845D01*
X61632Y299942D01*
X61646Y300247D01*
X61715Y300344D01*
X61777Y300406D01*
X61888Y300434D01*
X62235Y300448D01*
X62277Y300462D01*
X62505Y300455D01*
X67179Y300469D01*
X67262Y300483D01*
X67304Y300524D01*
X67331Y300621D01*
X67325Y301641D01*
X67331Y301772D01*
X67318Y301814D01*
X67304Y301994D01*
X67290Y302133D01*
X67283Y302292D01*
X67290Y302341D01*
X67276Y302383D01*
X67234Y302452D01*
X67158Y302528D01*
X67061Y302556D01*
X66603Y302570D01*
X66562Y302584D01*
X66465Y302597D01*
X66284Y302584D01*
X66187Y302597D01*
X66014Y302591D01*
X61687Y302604D01*
X61639Y302625D01*
X61604Y302701D01*
X61611Y304151D01*
X61604Y304310D01*
X61618Y304352D01*
X61611Y304580D01*
X61625Y304650D01*
X61639Y304886D01*
X61652Y305066D01*
X61673Y305087D01*
X61687Y305114D01*
X61764Y305191D01*
X61791Y305205D01*
X61833Y305219D01*
X62214Y305239D01*
X62270Y305253D01*
X62401Y305260D01*
X62443Y305246D01*
X62693Y305260D01*
X62734Y305246D01*
X62873Y305260D01*
X68184Y305274D01*
X68233Y305309D01*
X68261Y305406D01*
X68254Y306550D01*
X68261Y306709D01*
X68247Y306751D01*
X68261Y306987D01*
X68247Y307028D01*
X68233Y307084D01*
X68212Y307562D01*
X68191Y307611D01*
X68163Y307638D01*
X68150Y307666D01*
X68129Y307687D01*
X68101Y307701D01*
X68073Y307729D01*
X68018Y307742D01*
X67553Y307763D01*
X67484Y307777D01*
X67311Y307784D01*
D02*
G37*
G36*
X36690D02*
X36649Y307770D01*
X36510Y307784D01*
X28120Y307770D01*
X28071Y307722D01*
X28058Y307624D01*
X28065Y305940D01*
X28058Y305794D01*
X28071Y305752D01*
X28085Y305655D01*
X28106Y305219D01*
X28127Y305170D01*
X28182Y305114D01*
X28189Y305094D01*
X28217Y305080D01*
X28245Y305052D01*
X28342Y305038D01*
X28765Y305017D01*
X28834Y305004D01*
X29008Y304997D01*
X29049Y305010D01*
X29188Y304997D01*
X30041Y304990D01*
X30159Y304997D01*
X30200Y304983D01*
X30429Y304990D01*
X30602Y304983D01*
X30644Y304997D01*
X30762Y304976D01*
X31199Y304941D01*
X31330Y304809D01*
X31344Y304754D01*
Y304629D01*
Y304615D01*
X31358Y304518D01*
X31372Y304310D01*
X31386Y304268D01*
X31372Y304130D01*
X31386Y303922D01*
X31372Y303880D01*
X31386Y303645D01*
X31372Y303603D01*
X31386Y303464D01*
X31400Y295338D01*
X31435Y295303D01*
X31490Y295289D01*
X31587Y295275D01*
X33078Y295282D01*
X33237Y295275D01*
X33279Y295289D01*
X33501Y295275D01*
X33542Y295289D01*
X33639Y295303D01*
X34076Y295324D01*
X34146Y295352D01*
X34243Y295449D01*
X34270Y295546D01*
X34284Y295989D01*
X34298Y296031D01*
X34312Y296170D01*
X34298Y296308D01*
X34312Y296406D01*
X34305Y296579D01*
X34319Y303818D01*
X34326Y303894D01*
X34312Y303936D01*
X34326Y304185D01*
X34312Y304227D01*
X34326Y304380D01*
X34340Y304421D01*
X34347Y304692D01*
X34340Y304698D01*
X34354Y304740D01*
X34367Y304809D01*
X34499Y304941D01*
X34596Y304955D01*
X34811Y304962D01*
X34846Y304955D01*
X34887Y304969D01*
X35005Y304990D01*
X35082Y304997D01*
X35123Y304983D01*
X35380Y304990D01*
X35512Y304983D01*
X35553Y304997D01*
X35740Y304990D01*
X36462Y305004D01*
X36538Y305010D01*
X36579Y304997D01*
X36788Y305010D01*
X36829Y305024D01*
X37294Y305045D01*
X37467Y305149D01*
X37502Y305184D01*
X37557Y305281D01*
X37599Y305378D01*
X37620Y305856D01*
X37633Y305926D01*
X37640Y306057D01*
X37626Y306099D01*
X37640Y306376D01*
X37626Y306418D01*
X37640Y306598D01*
X37626Y306848D01*
X37640Y306890D01*
X37626Y307042D01*
X37613Y307084D01*
X37592Y307562D01*
X37571Y307611D01*
X37509Y307687D01*
X37425Y307742D01*
X36933Y307763D01*
X36864Y307777D01*
X36690Y307784D01*
D02*
G37*
G36*
X41475D02*
X39214D01*
X38909Y307770D01*
X38861Y307736D01*
X38847Y307680D01*
X38840Y307631D01*
X38847Y307541D01*
X38833Y307500D01*
X38847Y307403D01*
X38861Y295338D01*
X38909Y295289D01*
X39048Y295275D01*
X41558Y295289D01*
X41606Y295324D01*
X41634Y295421D01*
X41620Y307722D01*
X41572Y307770D01*
X41475Y307784D01*
D02*
G37*
G36*
X76796Y293680D02*
X76755Y293666D01*
X76547Y293680D01*
X76505Y293666D01*
X76276Y293673D01*
X76193Y293660D01*
X75999Y293646D01*
X75950Y293639D01*
X75936D01*
X75777Y293632D01*
X75701Y293639D01*
X75659Y293625D01*
X75631Y293611D01*
X75590Y293570D01*
X75562Y293556D01*
X75541Y293535D01*
X75527Y293507D01*
X75500Y293438D01*
X75479Y293029D01*
X75465Y292918D01*
X75451Y281477D01*
X75444Y281387D01*
X75458Y281345D01*
X75472Y281220D01*
X75507Y281185D01*
X75604Y281172D01*
X83404Y281178D01*
X83591Y281172D01*
X83633Y281185D01*
X83772Y281199D01*
X84167Y281220D01*
X84271Y281283D01*
X84299Y281296D01*
X84347Y281331D01*
X84361Y281359D01*
X85706Y282704D01*
X85720Y282732D01*
X85803Y282815D01*
X85831Y282884D01*
X85880Y283016D01*
X85900Y283078D01*
X85914Y283134D01*
X85935Y283460D01*
X85956Y283869D01*
X85970Y285089D01*
X85963Y290754D01*
X85970Y290844D01*
X85956Y290886D01*
X85963Y291129D01*
X85949Y291198D01*
X85921Y291572D01*
X85914Y291635D01*
X85928Y291677D01*
X85914Y291732D01*
X85845Y291857D01*
X85783Y291933D01*
X85706Y291996D01*
X85693Y292023D01*
X85630Y292086D01*
X85602Y292099D01*
X85568Y292134D01*
X85554Y292162D01*
X85491Y292224D01*
X85464Y292238D01*
X85443Y292259D01*
X85429Y292287D01*
X85367Y292349D01*
X85339Y292363D01*
X85304Y292398D01*
X85290Y292425D01*
X85228Y292488D01*
X85200Y292502D01*
X85179Y292522D01*
X85166Y292550D01*
X85103Y292613D01*
X85075Y292626D01*
X85041Y292661D01*
X85027Y292689D01*
X84964Y292751D01*
X84937Y292765D01*
X84902Y292800D01*
X84888Y292827D01*
X84826Y292890D01*
X84798Y292904D01*
X84777Y292925D01*
X84763Y292952D01*
X84701Y293015D01*
X84673Y293029D01*
X84639Y293063D01*
X84625Y293091D01*
X84562Y293153D01*
X84535Y293167D01*
X84514Y293188D01*
X84500Y293216D01*
X84437Y293278D01*
X84410Y293292D01*
X84375Y293327D01*
X84361Y293354D01*
X84299Y293417D01*
X84271Y293431D01*
X84202Y293500D01*
X84174Y293514D01*
X84077Y293556D01*
X83987Y293590D01*
X83917Y293618D01*
X83834Y293632D01*
X83799Y293639D01*
X83758Y293625D01*
X83716Y293639D01*
X83335Y293660D01*
X82725Y293673D01*
X76796Y293680D01*
D02*
G37*
G36*
X47799D02*
X47757Y293666D01*
X47487Y293673D01*
X47480Y293666D01*
X47091Y293680D01*
X41752Y293666D01*
X41711Y293653D01*
X41315Y293632D01*
X41163Y293618D01*
X41093Y293590D01*
X40982Y293549D01*
X40913Y293521D01*
X40865Y293486D01*
X40823Y293445D01*
X40795Y293431D01*
X40767Y293403D01*
X40740Y293389D01*
X40719Y293368D01*
X40705Y293341D01*
X40643Y293278D01*
X40615Y293264D01*
X40580Y293230D01*
X40566Y293202D01*
X40504Y293140D01*
X40476Y293126D01*
X40442Y293091D01*
X40428Y293063D01*
X40365Y293001D01*
X40338Y292987D01*
X40317Y292966D01*
X40303Y292938D01*
X40227Y292862D01*
X40199Y292848D01*
X40178Y292827D01*
X40164Y292800D01*
X40102Y292737D01*
X40074Y292724D01*
X40040Y292689D01*
X40026Y292661D01*
X39963Y292599D01*
X39936Y292585D01*
X39915Y292564D01*
X39901Y292536D01*
X39838Y292474D01*
X39811Y292460D01*
X39776Y292425D01*
X39762Y292398D01*
X39714Y292349D01*
X39686Y292335D01*
X39651Y292301D01*
X39637Y292273D01*
X39575Y292210D01*
X39547Y292197D01*
X39513Y292162D01*
X39499Y292134D01*
X39450Y292086D01*
X39422Y292072D01*
X39374Y292023D01*
X39332Y291954D01*
X39263Y291857D01*
X39249Y291801D01*
X39228Y291670D01*
X39187Y291559D01*
X39166Y291482D01*
X39152Y291427D01*
X39131Y291032D01*
X39117Y290643D01*
X39110Y284077D01*
X39124Y284035D01*
X39138Y283453D01*
X39152Y283411D01*
X39166Y283203D01*
X39235Y283051D01*
X39249Y282995D01*
X39318Y282898D01*
X39360Y282857D01*
X39374Y282829D01*
X39450Y282752D01*
X39478Y282739D01*
X39499Y282718D01*
X39513Y282690D01*
X39589Y282614D01*
X39616Y282600D01*
X39651Y282551D01*
X39714Y282489D01*
X39741Y282475D01*
X39762Y282454D01*
X39776Y282427D01*
X39852Y282350D01*
X39880Y282337D01*
X39901Y282316D01*
X39915Y282288D01*
X39991Y282212D01*
X40019Y282198D01*
X40053Y282149D01*
X40116Y282087D01*
X40143Y282073D01*
X40178Y282024D01*
X40254Y281948D01*
X40282Y281934D01*
X40317Y281886D01*
X40379Y281823D01*
X40407Y281810D01*
X40428Y281789D01*
X40442Y281761D01*
X40518Y281685D01*
X40546Y281671D01*
X40566Y281650D01*
X40580Y281622D01*
X40657Y281546D01*
X40684Y281532D01*
X40719Y281484D01*
X40781Y281421D01*
X40809Y281407D01*
X40830Y281387D01*
X40844Y281359D01*
X40865Y281324D01*
X40892Y281310D01*
X41045Y281213D01*
X41523Y281192D01*
X41606Y281178D01*
X41794Y281172D01*
X41835Y281185D01*
X41932Y281172D01*
X48631Y281185D01*
X48665Y281220D01*
X48693Y281331D01*
X48686Y282600D01*
X48693Y282718D01*
X48679Y282759D01*
X48686Y283002D01*
X48672Y283085D01*
X48658Y283279D01*
X48644Y283460D01*
X48637Y283508D01*
X48651Y283550D01*
X48637Y283605D01*
X48624Y283647D01*
X48561Y283723D01*
X48534Y283751D01*
X48464Y283779D01*
X48014Y283800D01*
X47826Y283820D01*
X47667Y283813D01*
X43909Y283827D01*
X43090Y283841D01*
X42716Y283855D01*
X42411Y283869D01*
X42355Y283883D01*
X42286Y283911D01*
X42196Y283945D01*
X42140Y283959D01*
X42050Y284008D01*
X42036Y284063D01*
X42043Y290061D01*
X42036Y290220D01*
X42050Y290262D01*
X42064Y290317D01*
X42078Y290678D01*
X42140Y290754D01*
X42210Y290824D01*
X42321Y290851D01*
X42681Y290865D01*
X42723Y290879D01*
X42952Y290872D01*
X46696Y290886D01*
X47514Y290900D01*
X48097Y290942D01*
X48152Y290955D01*
X48270Y290990D01*
X48326Y291004D01*
X48464Y291018D01*
X48631Y291032D01*
X48665Y291066D01*
X48693Y291177D01*
X48686Y292446D01*
X48693Y292578D01*
X48679Y292619D01*
X48686Y292862D01*
X48672Y292931D01*
X48644Y293320D01*
X48637Y293368D01*
X48651Y293410D01*
X48637Y293465D01*
X48624Y293493D01*
X48561Y293570D01*
X48520Y293611D01*
X48423Y293639D01*
X48326Y293625D01*
X48284Y293639D01*
X47944Y293660D01*
X47861Y293673D01*
X47799Y293680D01*
D02*
G37*
G36*
X58685D02*
X58643Y293666D01*
X58539Y293646D01*
X58359Y293632D01*
X58310Y293611D01*
X58283Y293583D01*
X58255Y293570D01*
X58158Y293500D01*
X58088Y293417D01*
X58026Y293368D01*
X58012Y293341D01*
X57936Y293264D01*
X57908Y293251D01*
X57887Y293230D01*
X57874Y293202D01*
X57811Y293140D01*
X57783Y293126D01*
X57749Y293091D01*
X57735Y293063D01*
X57673Y293001D01*
X57645Y292987D01*
X57624Y292966D01*
X57610Y292938D01*
X57534Y292862D01*
X57506Y292848D01*
X57485Y292827D01*
X57471Y292800D01*
X57409Y292737D01*
X57381Y292724D01*
X57360Y292703D01*
X57347Y292675D01*
X57270Y292599D01*
X57242Y292585D01*
X57222Y292564D01*
X57208Y292536D01*
X57146Y292474D01*
X57118Y292460D01*
X57083Y292425D01*
X57069Y292398D01*
X57007Y292335D01*
X56979Y292321D01*
X56958Y292301D01*
X56944Y292273D01*
X56868Y292197D01*
X56840Y292183D01*
X56820Y292162D01*
X56806Y292134D01*
X56743Y292072D01*
X56716Y292058D01*
X56695Y292037D01*
X56681Y292009D01*
X56605Y291933D01*
X56577Y291919D01*
X56556Y291898D01*
X56542Y291871D01*
X56480Y291808D01*
X56452Y291794D01*
X56417Y291760D01*
X56403Y291732D01*
X56341Y291670D01*
X56313Y291656D01*
X56293Y291635D01*
X56279Y291607D01*
X56203Y291531D01*
X56175Y291517D01*
X56154Y291496D01*
X56140Y291469D01*
X56064Y291392D01*
X56036Y291378D01*
X55932Y291233D01*
X55967Y291170D01*
X56064Y291157D01*
X56168Y291150D01*
X56674Y291157D01*
X56716Y291143D01*
X56896Y291157D01*
X57416Y291136D01*
X57527Y291150D01*
X57561Y291157D01*
X57603Y291143D01*
X57742Y291129D01*
X58054Y291108D01*
X58130Y291059D01*
X58220Y290969D01*
X58234Y290914D01*
X58255Y290532D01*
X58269Y290477D01*
X58276Y290345D01*
X58262Y290304D01*
X58276Y290054D01*
X58262Y290012D01*
X58276Y289915D01*
X58269Y288660D01*
X58276Y288487D01*
X58262Y288445D01*
X58276Y288223D01*
X58248Y288154D01*
X58227Y287759D01*
X58158Y287648D01*
X58102Y287565D01*
X58075Y287551D01*
X57964Y287481D01*
X57867Y287454D01*
X57790Y287461D01*
X57541Y287447D01*
X57485Y287433D01*
X57326Y287426D01*
X57284Y287440D01*
X57146Y287426D01*
X54310Y287433D01*
X54136Y287426D01*
X54067Y287454D01*
X53810Y287461D01*
X53734Y287454D01*
X53692Y287468D01*
X53665Y287481D01*
X53581Y287537D01*
X53554Y287551D01*
X53491Y287599D01*
X53477Y287627D01*
X53408Y287724D01*
X53366Y287821D01*
X53353Y288085D01*
X53339Y288251D01*
X53290Y288300D01*
X53235Y288286D01*
X53207Y288258D01*
X53179Y288244D01*
X53013Y288078D01*
X52985Y288064D01*
X52964Y288043D01*
X52950Y288015D01*
X52874Y287939D01*
X52846Y287925D01*
X52777Y287842D01*
X52722Y287787D01*
X52694Y287773D01*
X52659Y287724D01*
X52611Y287676D01*
X52583Y287662D01*
X52548Y287613D01*
X52486Y287551D01*
X52458Y287537D01*
X52437Y287516D01*
X52424Y287488D01*
X52347Y287412D01*
X52319Y287398D01*
X52299Y287377D01*
X52285Y287350D01*
X52208Y287273D01*
X52188Y287267D01*
X52174Y287239D01*
X52084Y287149D01*
X52056Y287135D01*
X52021Y287100D01*
X52007Y287072D01*
X51931Y286996D01*
X51910Y286989D01*
X51897Y286961D01*
X51806Y286871D01*
X51779Y286857D01*
X51744Y286809D01*
X51681Y286747D01*
X51654Y286733D01*
X51633Y286712D01*
X51619Y286684D01*
X51543Y286608D01*
X51515Y286594D01*
X51494Y286573D01*
X51480Y286545D01*
X51390Y286455D01*
X51370Y286448D01*
X51356Y286421D01*
X51266Y286330D01*
X51238Y286317D01*
X51203Y286268D01*
X51155Y286220D01*
X51127Y286206D01*
X51106Y286185D01*
X51092Y286157D01*
X51016Y286081D01*
X50988Y286067D01*
X50967Y286046D01*
X50953Y286018D01*
X50877Y285942D01*
X50849Y285928D01*
X50815Y285880D01*
X50739Y285804D01*
X50711Y285790D01*
X50690Y285769D01*
X50593Y285561D01*
X50607Y285450D01*
X50593Y285408D01*
X50572Y285082D01*
X50558Y284999D01*
X50551Y284923D01*
X50565Y284881D01*
X50558Y284625D01*
X50565Y284479D01*
X50551Y284438D01*
X50558Y284250D01*
X50551Y281317D01*
X50565Y281276D01*
X50579Y281220D01*
X50614Y281185D01*
X50669Y281172D01*
X53290Y281185D01*
X53325Y281220D01*
X53353Y281331D01*
X53359Y283793D01*
X53353Y283897D01*
X53366Y283938D01*
X53380Y284535D01*
X53394Y284576D01*
X53408Y284729D01*
X53464Y284853D01*
X53477Y284909D01*
X53505Y284978D01*
X53540Y285013D01*
X53595Y285027D01*
X53727Y285075D01*
X53796Y285103D01*
X53852Y285117D01*
X54157Y285131D01*
X54545Y285145D01*
X55350Y285159D01*
X56272Y285166D01*
X56313Y285152D01*
X57464Y285138D01*
X57506Y285124D01*
X57825Y285110D01*
X57977Y285041D01*
X58068Y285020D01*
X58116Y284985D01*
X58151Y284909D01*
X58172Y284819D01*
X58234Y284673D01*
X58255Y284250D01*
X58269Y283696D01*
X58283Y281283D01*
X58296Y281227D01*
X58338Y281185D01*
X58394Y281172D01*
X61015Y281185D01*
X61049Y281220D01*
X61063Y281276D01*
X61070Y282115D01*
X61063Y282163D01*
X61077Y282205D01*
X61063Y282302D01*
X61077Y282857D01*
Y290096D01*
Y290109D01*
X61063Y290248D01*
X61049Y291191D01*
X61035Y291233D01*
X61021Y291607D01*
X60966Y291732D01*
X60952Y291787D01*
X60925Y291857D01*
X60911Y291884D01*
X60841Y291954D01*
X60827Y291982D01*
X60765Y292058D01*
X60689Y292120D01*
X60626Y292197D01*
X60550Y292259D01*
X60488Y292335D01*
X60411Y292398D01*
X60349Y292474D01*
X60321Y292488D01*
X60273Y292536D01*
X60259Y292564D01*
X60210Y292613D01*
X60182Y292626D01*
X60134Y292675D01*
X60120Y292703D01*
X60086Y292737D01*
X60058Y292751D01*
X60009Y292800D01*
X59995Y292827D01*
X59947Y292876D01*
X59919Y292890D01*
X59871Y292938D01*
X59857Y292966D01*
X59808Y293015D01*
X59780Y293029D01*
X59732Y293077D01*
X59718Y293105D01*
X59683Y293140D01*
X59656Y293153D01*
X59607Y293202D01*
X59593Y293230D01*
X59545Y293278D01*
X59517Y293292D01*
X59468Y293341D01*
X59454Y293368D01*
X59406Y293417D01*
X59378Y293431D01*
X59344Y293465D01*
X59330Y293493D01*
X59281Y293542D01*
X59253Y293556D01*
X59156Y293625D01*
X59101Y293639D01*
X58907Y293653D01*
X58865Y293666D01*
X58685Y293680D01*
D02*
G37*
G36*
X54150Y314981D02*
X54108Y314968D01*
X54039Y314926D01*
X54018Y314850D01*
X54011Y296385D01*
X54018Y296211D01*
X54004Y296170D01*
X54018Y295962D01*
X54004Y295920D01*
X54018Y295684D01*
X53991Y295615D01*
X53984Y295525D01*
X53991Y295449D01*
X53977Y295407D01*
X53963Y295199D01*
X53893Y295102D01*
X53852Y295033D01*
X53831Y295012D01*
X53803Y294998D01*
X53741Y294935D01*
X53727Y294908D01*
X53706Y294887D01*
X53678Y294873D01*
X53616Y294811D01*
X53602Y294783D01*
X53568Y294748D01*
X53540Y294734D01*
X53477Y294672D01*
X53464Y294644D01*
X53429Y294610D01*
X53401Y294596D01*
X53353Y294547D01*
X53339Y294519D01*
X53304Y294485D01*
X53276Y294471D01*
X53214Y294408D01*
X53200Y294381D01*
X53165Y294346D01*
X53138Y294332D01*
X53075Y294270D01*
X53061Y294242D01*
X53027Y294207D01*
X52957Y294166D01*
X52888Y294096D01*
X52791Y294069D01*
X52722Y294027D01*
X52666Y293972D01*
X52638Y293958D01*
X52562Y293895D01*
X52500Y293819D01*
X52424Y293757D01*
X52410Y293729D01*
X52347Y293666D01*
X52319Y293653D01*
X52285Y293618D01*
X52271Y293590D01*
X52222Y293542D01*
X52195Y293528D01*
X52160Y293493D01*
X52146Y293465D01*
X52084Y293403D01*
X52056Y293389D01*
X52021Y293354D01*
X52007Y293327D01*
X51959Y293278D01*
X51931Y293264D01*
X51897Y293230D01*
X51883Y293202D01*
X51820Y293140D01*
X51792Y293126D01*
X51758Y293091D01*
X51744Y293063D01*
X51695Y293015D01*
X51668Y293001D01*
X51633Y292966D01*
X51619Y292938D01*
X51557Y292876D01*
X51529Y292862D01*
X51494Y292827D01*
X51480Y292800D01*
X51432Y292751D01*
X51404Y292737D01*
X51356Y292689D01*
X51342Y292661D01*
X51293Y292613D01*
X51266Y292599D01*
X51231Y292564D01*
X51217Y292536D01*
X51155Y292474D01*
X51127Y292460D01*
X51092Y292425D01*
X51078Y292398D01*
X51016Y292335D01*
X50988Y292321D01*
X50953Y292287D01*
X50940Y292259D01*
X50891Y292210D01*
X50863Y292197D01*
X50829Y292162D01*
X50815Y292134D01*
X50766Y292086D01*
X50739Y292072D01*
X50690Y292023D01*
X50676Y291996D01*
X50628Y291947D01*
X50600Y291933D01*
X50565Y291898D01*
X50551Y291871D01*
X50489Y291808D01*
X50461Y291794D01*
X50427Y291760D01*
X50413Y291732D01*
X50350Y291670D01*
X50322Y291656D01*
X50302Y291635D01*
X50288Y291607D01*
X50225Y291545D01*
X50198Y291531D01*
X50149Y291482D01*
X50135Y291455D01*
X50101Y291420D01*
X50073Y291406D01*
X50024Y291357D01*
X50010Y291330D01*
X49962Y291281D01*
X49934Y291267D01*
X49900Y291233D01*
X49886Y291205D01*
X49823Y291143D01*
X49795Y291129D01*
X49761Y291094D01*
X49747Y291066D01*
X49685Y291004D01*
X49657Y290990D01*
X49636Y290969D01*
X49622Y290942D01*
X49560Y290879D01*
X49532Y290865D01*
X49483Y290817D01*
X49470Y290789D01*
X49435Y290754D01*
X49407Y290740D01*
X49359Y290692D01*
X49345Y290664D01*
X49296Y290616D01*
X49268Y290602D01*
X49234Y290567D01*
X49220Y290539D01*
X49158Y290477D01*
X49130Y290463D01*
X49095Y290428D01*
X49081Y290401D01*
X49033Y290352D01*
X49005Y290338D01*
X48956Y290290D01*
X48943Y290262D01*
X48894Y290213D01*
X48866Y290200D01*
X48832Y290165D01*
X48818Y290137D01*
X48755Y290075D01*
X48728Y290061D01*
X48707Y290040D01*
X48693Y290012D01*
X48631Y289950D01*
X48603Y289936D01*
X48568Y289901D01*
X48554Y289874D01*
X48492Y289811D01*
X48464Y289797D01*
X48429Y289763D01*
X48416Y289735D01*
X48353Y289673D01*
X48326Y289659D01*
X48305Y289638D01*
X48291Y289610D01*
X48228Y289548D01*
X48201Y289534D01*
X48166Y289499D01*
X48152Y289471D01*
X48090Y289409D01*
X48062Y289395D01*
X48027Y289361D01*
X48014Y289333D01*
X47951Y289270D01*
X47923Y289256D01*
X47902Y289236D01*
X47889Y289208D01*
X47861Y289180D01*
X47847Y289153D01*
X47792Y289097D01*
X47778Y289069D01*
X47750Y289000D01*
X47736Y288944D01*
X47681Y288820D01*
X47667Y288681D01*
X47646Y288272D01*
X47632Y287800D01*
X47625Y287447D01*
X47639Y287405D01*
X47653Y286740D01*
X47667Y286698D01*
X47681Y286421D01*
X47736Y286296D01*
X47750Y286240D01*
X47819Y286115D01*
X47875Y286060D01*
X47889Y286032D01*
X47937Y285970D01*
X47965Y285956D01*
X48041Y285880D01*
X48048Y285859D01*
X48076Y285845D01*
X48131Y285790D01*
X48159Y285776D01*
X48187Y285748D01*
X48242Y285734D01*
X48270Y285762D01*
X48298Y285776D01*
X48339Y285817D01*
X48367Y285831D01*
X48416Y285880D01*
X48429Y285907D01*
X48478Y285956D01*
X48506Y285970D01*
X48554Y286018D01*
X48568Y286046D01*
X48617Y286095D01*
X48644Y286108D01*
X48693Y286157D01*
X48707Y286185D01*
X48741Y286220D01*
X48769Y286233D01*
X48818Y286282D01*
X48832Y286310D01*
X48880Y286358D01*
X48908Y286372D01*
X48956Y286421D01*
X48970Y286448D01*
X49019Y286497D01*
X49047Y286511D01*
X49081Y286545D01*
X49095Y286573D01*
X49144Y286622D01*
X49172Y286635D01*
X49220Y286684D01*
X49234Y286712D01*
X49282Y286760D01*
X49310Y286774D01*
X49359Y286823D01*
X49373Y286850D01*
X49407Y286885D01*
X49435Y286899D01*
X49511Y286961D01*
X49546Y286996D01*
X49615Y287024D01*
X49705Y287059D01*
X49782Y287135D01*
X49809Y287149D01*
X49886Y287211D01*
X49900Y287239D01*
X49976Y287315D01*
X50003Y287329D01*
X50038Y287377D01*
X50101Y287440D01*
X50128Y287454D01*
X50149Y287474D01*
X50163Y287502D01*
X50225Y287565D01*
X50253Y287579D01*
X50274Y287599D01*
X50288Y287627D01*
X50364Y287703D01*
X50392Y287717D01*
X50413Y287738D01*
X50427Y287766D01*
X50489Y287828D01*
X50517Y287842D01*
X50537Y287863D01*
X50551Y287891D01*
X50628Y287967D01*
X50655Y287981D01*
X50690Y288029D01*
X50766Y288106D01*
X50787Y288113D01*
X50801Y288140D01*
X50891Y288230D01*
X50919Y288244D01*
X50940Y288265D01*
X50953Y288293D01*
X51030Y288369D01*
X51058Y288383D01*
X51078Y288404D01*
X51092Y288431D01*
X51168Y288508D01*
X51196Y288522D01*
X51266Y288605D01*
X51307Y288646D01*
X51335Y288660D01*
X51404Y288743D01*
X51432Y288771D01*
X51453Y288778D01*
X51467Y288806D01*
X51557Y288896D01*
X51585Y288910D01*
X51605Y288931D01*
X51619Y288958D01*
X51695Y289035D01*
X51723Y289049D01*
X51744Y289069D01*
X51758Y289097D01*
X51834Y289173D01*
X51862Y289187D01*
X51897Y289236D01*
X51973Y289312D01*
X52000Y289326D01*
X52035Y289374D01*
X52098Y289437D01*
X52118Y289444D01*
X52132Y289471D01*
X52222Y289562D01*
X52250Y289576D01*
X52271Y289596D01*
X52285Y289624D01*
X52361Y289700D01*
X52389Y289714D01*
X52410Y289735D01*
X52424Y289763D01*
X52500Y289839D01*
X52527Y289853D01*
X52562Y289901D01*
X52625Y289964D01*
X52652Y289978D01*
X52673Y289998D01*
X52687Y290026D01*
X52763Y290103D01*
X52791Y290116D01*
X52860Y290200D01*
X52888Y290227D01*
X52916Y290241D01*
X52937Y290262D01*
X52950Y290290D01*
X53027Y290366D01*
X53054Y290380D01*
X53075Y290401D01*
X53089Y290428D01*
X53165Y290505D01*
X53193Y290518D01*
X53228Y290567D01*
X53290Y290630D01*
X53318Y290643D01*
X53339Y290664D01*
X53353Y290692D01*
X53429Y290768D01*
X53457Y290782D01*
X53491Y290831D01*
X53554Y290893D01*
X53581Y290907D01*
X53602Y290928D01*
X53616Y290955D01*
X53678Y291018D01*
X53706Y291032D01*
X53741Y291066D01*
X53755Y291094D01*
X53831Y291170D01*
X53852Y291177D01*
X53866Y291205D01*
X53956Y291295D01*
X53984Y291309D01*
X54004Y291330D01*
X54018Y291357D01*
X54081Y291420D01*
X54108Y291434D01*
X54129Y291455D01*
X54143Y291482D01*
X54219Y291559D01*
X54247Y291572D01*
X54268Y291593D01*
X54282Y291621D01*
X54344Y291683D01*
X54372Y291697D01*
X54407Y291732D01*
X54420Y291760D01*
X54497Y291836D01*
X54524Y291850D01*
X54545Y291871D01*
X54559Y291898D01*
X54635Y291975D01*
X54656Y291982D01*
X54670Y292009D01*
X54746Y292086D01*
X54774Y292099D01*
X54795Y292120D01*
X54809Y292148D01*
X54885Y292224D01*
X54913Y292238D01*
X54934Y292259D01*
X54947Y292287D01*
X55024Y292363D01*
X55051Y292377D01*
X55072Y292398D01*
X55086Y292425D01*
X55149Y292488D01*
X55176Y292502D01*
X55197Y292522D01*
X55211Y292550D01*
X55287Y292626D01*
X55315Y292640D01*
X55336Y292661D01*
X55350Y292689D01*
X55426Y292765D01*
X55454Y292779D01*
X55488Y292827D01*
X55551Y292890D01*
X55578Y292904D01*
X55599Y292925D01*
X55613Y292952D01*
X55689Y293029D01*
X55717Y293043D01*
X55738Y293063D01*
X55752Y293091D01*
X55814Y293153D01*
X55842Y293167D01*
X55863Y293188D01*
X55876Y293216D01*
X55953Y293292D01*
X55981Y293306D01*
X56001Y293327D01*
X56015Y293354D01*
X56091Y293431D01*
X56119Y293445D01*
X56189Y293528D01*
X56216Y293556D01*
X56244Y293570D01*
X56265Y293590D01*
X56279Y293618D01*
X56355Y293694D01*
X56383Y293708D01*
X56403Y293729D01*
X56417Y293757D01*
X56480Y293833D01*
X56515Y293868D01*
X56542Y293937D01*
X56577Y294027D01*
X56632Y294110D01*
X56667Y294187D01*
X56695Y294256D01*
X56729Y294346D01*
X56764Y294464D01*
X56785Y294873D01*
X56799Y295247D01*
X56806Y295365D01*
Y295379D01*
X56799Y312263D01*
X56806Y312464D01*
X56792Y312506D01*
X56778Y312603D01*
X56757Y313040D01*
X56695Y313144D01*
X56681Y313172D01*
X56632Y313234D01*
X56605Y313248D01*
X56542Y313310D01*
X56528Y313338D01*
X56508Y313359D01*
X56480Y313373D01*
X56390Y313463D01*
X56376Y313491D01*
X56327Y313525D01*
X56265Y313588D01*
X56251Y313615D01*
X56230Y313636D01*
X56203Y313650D01*
X56126Y313726D01*
X56112Y313754D01*
X56064Y313789D01*
X56001Y313851D01*
X55988Y313879D01*
X55967Y313900D01*
X55939Y313914D01*
X55863Y313990D01*
X55849Y314018D01*
X55766Y314087D01*
X55724Y314129D01*
X55710Y314156D01*
X55627Y314226D01*
X55599Y314253D01*
X55585Y314281D01*
X55564Y314302D01*
X55537Y314316D01*
X55461Y314392D01*
X55447Y314420D01*
X55398Y314454D01*
X55336Y314517D01*
X55322Y314545D01*
X55301Y314565D01*
X55273Y314579D01*
X55197Y314656D01*
X55183Y314683D01*
X55162Y314704D01*
X55135Y314718D01*
X55058Y314780D01*
X55038Y314801D01*
X55010Y314815D01*
X54941Y314843D01*
X54809Y314891D01*
X54732Y314926D01*
X54642Y314947D01*
X54573Y314961D01*
X54407Y314974D01*
X54150Y314981D01*
D02*
G37*
G36*
X69335Y293680D02*
X62887Y293666D01*
X62824Y293618D01*
X62811Y293563D01*
X62824Y281220D01*
X62859Y281185D01*
X62915Y281172D01*
X64766Y281178D01*
X64953Y281172D01*
X64995Y281185D01*
X65133Y281199D01*
X65515Y281220D01*
X65563Y281241D01*
X65667Y281345D01*
X65681Y281400D01*
X65702Y281823D01*
X65730Y282045D01*
X65723Y282274D01*
X65737Y282316D01*
X65723Y282357D01*
X65730Y282628D01*
X65716Y283571D01*
X65702Y283751D01*
X65688Y283987D01*
X65674Y284153D01*
X65660Y284209D01*
X65633Y284278D01*
X65598Y284396D01*
X65612Y284535D01*
X65723Y284770D01*
X65743Y284958D01*
X65778Y285006D01*
X65855Y285027D01*
X67276Y285020D01*
X67449Y285027D01*
X67491Y285013D01*
X67727Y285027D01*
X67796Y284999D01*
X68191Y284978D01*
X68274Y284923D01*
X68309Y284888D01*
X68337Y284874D01*
X68372Y284840D01*
X68399Y284743D01*
X68455Y284646D01*
X68524Y284576D01*
X68538Y284548D01*
X68600Y284472D01*
X68635Y284438D01*
X68663Y284368D01*
X68677Y284313D01*
X68774Y284160D01*
X68822Y284028D01*
X68857Y283980D01*
X68912Y283924D01*
X68926Y283897D01*
X68989Y283820D01*
X69037Y283772D01*
X69100Y283598D01*
X69134Y283564D01*
X69148Y283536D01*
X69190Y283439D01*
X69224Y283349D01*
X69314Y283259D01*
X69356Y283189D01*
X69426Y283120D01*
X69467Y283023D01*
X69481Y282967D01*
X69550Y282870D01*
X69564Y282843D01*
X69592Y282773D01*
X69626Y282683D01*
X69682Y282600D01*
X69717Y282524D01*
X69751Y282434D01*
X69786Y282385D01*
X69855Y282316D01*
X69897Y282246D01*
X69966Y282177D01*
X70015Y282045D01*
X70084Y281934D01*
X70119Y281844D01*
X70188Y281719D01*
X70244Y281664D01*
X70258Y281636D01*
X70320Y281560D01*
X70355Y281525D01*
X70368Y281497D01*
X70396Y281428D01*
X70410Y281373D01*
X70459Y281310D01*
X70486Y281296D01*
X70514Y281269D01*
X70542Y281255D01*
X70570Y281227D01*
X70667Y281213D01*
X71076Y281192D01*
X71159Y281178D01*
X71360Y281172D01*
X71402Y281185D01*
X71457Y281172D01*
X73537Y281185D01*
X73558Y281206D01*
X73572Y281262D01*
X73558Y281373D01*
X73489Y281470D01*
X73461Y281539D01*
X73426Y281629D01*
X73405Y281650D01*
X73392Y281678D01*
X73336Y281733D01*
X73322Y281761D01*
X73260Y281837D01*
X73211Y281886D01*
X73163Y282017D01*
X73128Y282066D01*
X73087Y282108D01*
X73073Y282135D01*
X73010Y282225D01*
X72990Y282232D01*
X72983Y282253D01*
X72962Y282260D01*
X72948Y282288D01*
X72920Y282357D01*
X72885Y282447D01*
X72865Y282468D01*
X72851Y282496D01*
X72823Y282524D01*
X72761Y282697D01*
X72684Y282773D01*
X72670Y282801D01*
X72573Y282926D01*
X72546Y282954D01*
X72518Y283023D01*
X72504Y283078D01*
X72407Y283231D01*
X72358Y283363D01*
X72324Y283411D01*
X72296Y283425D01*
X72282Y283453D01*
X72255Y283481D01*
X72213Y283550D01*
X72144Y283619D01*
X72095Y283751D01*
X72026Y283862D01*
X71991Y283952D01*
X71963Y284021D01*
X71901Y284098D01*
X71866Y284132D01*
X71825Y284202D01*
X71755Y284271D01*
X71727Y284340D01*
X71693Y284431D01*
X71658Y284479D01*
X71603Y284562D01*
X71582Y284639D01*
X71554Y284708D01*
X71492Y284826D01*
X71464Y284923D01*
X71478Y285200D01*
X71547Y285297D01*
X71575Y285325D01*
X71617Y285394D01*
X71651Y285429D01*
X71672Y285436D01*
X71679Y285443D01*
X71714Y285478D01*
X71727Y285505D01*
X71790Y285568D01*
X71818Y285582D01*
X71852Y285616D01*
X71866Y285644D01*
X71929Y285706D01*
X71956Y285720D01*
X71977Y285741D01*
X71991Y285769D01*
X72053Y285831D01*
X72081Y285845D01*
X72116Y285880D01*
X72130Y285907D01*
X72192Y285970D01*
X72220Y285984D01*
X72241Y286005D01*
X72255Y286032D01*
X72317Y286095D01*
X72345Y286108D01*
X72379Y286143D01*
X72393Y286171D01*
X72456Y286233D01*
X72483Y286247D01*
X72518Y286282D01*
X72532Y286310D01*
X72594Y286372D01*
X72622Y286386D01*
X72643Y286407D01*
X72657Y286434D01*
X72719Y286497D01*
X72747Y286511D01*
X72782Y286545D01*
X72795Y286573D01*
X72858Y286635D01*
X72885Y286649D01*
X72920Y286684D01*
X72934Y286712D01*
X72983Y286760D01*
X73010Y286774D01*
X73059Y286823D01*
X73073Y286850D01*
X73135Y286927D01*
X73156Y286948D01*
X73184Y287017D01*
X73197Y287072D01*
X73253Y287197D01*
X73267Y287253D01*
X73288Y287579D01*
X73309Y287988D01*
X73315Y288522D01*
X73309Y288528D01*
X73322Y288570D01*
X73315Y290310D01*
X73322Y290415D01*
X73309Y290456D01*
X73295Y291261D01*
X73281Y291302D01*
X73260Y291628D01*
X73197Y291774D01*
X73163Y291864D01*
X73114Y291940D01*
X73073Y291982D01*
X73059Y292009D01*
X72983Y292086D01*
X72955Y292099D01*
X72934Y292120D01*
X72920Y292148D01*
X72844Y292224D01*
X72816Y292238D01*
X72795Y292259D01*
X72782Y292287D01*
X72566Y292502D01*
X72546Y292509D01*
X72532Y292536D01*
X72442Y292626D01*
X72414Y292640D01*
X72379Y292689D01*
X72317Y292751D01*
X72289Y292765D01*
X72268Y292786D01*
X72255Y292814D01*
X72178Y292890D01*
X72151Y292904D01*
X72130Y292925D01*
X72116Y292952D01*
X71915Y293153D01*
X71887Y293167D01*
X71866Y293188D01*
X71852Y293216D01*
X71776Y293292D01*
X71748Y293306D01*
X71679Y293389D01*
X71651Y293417D01*
X71624Y293431D01*
X71554Y293500D01*
X71526Y293514D01*
X71429Y293556D01*
X71339Y293590D01*
X71270Y293618D01*
X71187Y293632D01*
X70882Y293646D01*
X70472Y293666D01*
X69335Y293680D01*
D02*
G37*
G36*
X33140Y293666D02*
X33029Y293653D01*
X33008Y293632D01*
X32981Y293563D01*
X33001Y292626D01*
X33015Y292335D01*
X33029Y292099D01*
X33043Y291989D01*
X33057Y291933D01*
X33071Y291864D01*
X33085Y291780D01*
X33105Y291593D01*
X33119Y291496D01*
X33133Y291274D01*
X33168Y291073D01*
X33189Y290997D01*
X33244Y290775D01*
X33258Y290636D01*
X33272Y290484D01*
X33300Y290415D01*
X33341Y290262D01*
X33355Y290207D01*
X33383Y290040D01*
X33404Y289867D01*
X33418Y289797D01*
X33431Y289742D01*
X33480Y289583D01*
X33494Y289527D01*
X33521Y289333D01*
X33542Y289173D01*
X33556Y289104D01*
X33598Y288993D01*
X33619Y288917D01*
X33646Y288806D01*
X33660Y288667D01*
X33681Y288577D01*
X33730Y288459D01*
X33771Y288362D01*
X33785Y288265D01*
X33799Y288209D01*
X33834Y288119D01*
X33896Y287974D01*
X33924Y287877D01*
X33938Y287780D01*
X34021Y287599D01*
X34049Y287502D01*
X34076Y287377D01*
X34146Y287225D01*
X34173Y287128D01*
X34187Y287072D01*
X34208Y286982D01*
X34277Y286830D01*
X34298Y286767D01*
X34326Y286656D01*
X34340Y286573D01*
X34409Y286462D01*
X34444Y286372D01*
X34513Y286220D01*
X34576Y286074D01*
X34596Y285956D01*
X34631Y285866D01*
X34728Y285658D01*
X34839Y285422D01*
X34853Y285325D01*
X34874Y285249D01*
X34936Y285131D01*
X34978Y285034D01*
X35657Y283661D01*
X35699Y283591D01*
X35768Y283522D01*
X35782Y283494D01*
X35844Y283418D01*
X35865Y283397D01*
X35879Y283370D01*
X35935Y283245D01*
X35990Y283148D01*
X36059Y282995D01*
X36129Y282870D01*
X36184Y282746D01*
X36240Y282649D01*
X36309Y282579D01*
X36323Y282551D01*
X36385Y282475D01*
X36420Y282440D01*
X36448Y282371D01*
X36462Y282316D01*
X36559Y282163D01*
X36572Y282108D01*
X36642Y281983D01*
X36697Y281927D01*
X36711Y281900D01*
X36878Y281733D01*
X36891Y281705D01*
X36933Y281664D01*
X36947Y281636D01*
X36975Y281567D01*
X37044Y281442D01*
X37113Y281373D01*
X37127Y281345D01*
X37169Y281303D01*
X37183Y281276D01*
X37224Y281234D01*
X37273Y281102D01*
X37342Y281019D01*
X37377Y280970D01*
X37405Y280943D01*
X37411Y280922D01*
X37439Y280908D01*
X37529Y280818D01*
X37543Y280790D01*
X37599Y280735D01*
X37613Y280707D01*
X37654Y280610D01*
X37668Y280568D01*
X37731Y280492D01*
X37765Y280457D01*
X37779Y280430D01*
X38084Y280125D01*
X38098Y280097D01*
X38140Y280055D01*
X38153Y280028D01*
X38209Y279889D01*
X38278Y279820D01*
X38292Y279792D01*
X38354Y279715D01*
X38431Y279653D01*
X38493Y279577D01*
X38570Y279514D01*
X38583Y279487D01*
X38632Y279438D01*
X38660Y279424D01*
X38722Y279362D01*
X38736Y279334D01*
X38757Y279313D01*
X38784Y279299D01*
X40580Y277504D01*
X40594Y277476D01*
X40615Y277455D01*
X40643Y277441D01*
X40705Y277379D01*
X40719Y277351D01*
X40767Y277302D01*
X40795Y277289D01*
X40830Y277254D01*
X40844Y277226D01*
X40906Y277164D01*
X40934Y277150D01*
X40969Y277115D01*
X40982Y277087D01*
X41031Y277039D01*
X41059Y277025D01*
X41107Y276977D01*
X41121Y276949D01*
X41156Y276914D01*
X41184Y276900D01*
X41211Y276873D01*
X41239Y276859D01*
X41294Y276803D01*
X41364Y276775D01*
X41419Y276762D01*
X41447Y276734D01*
X41475Y276720D01*
X41502Y276692D01*
X41530Y276678D01*
X41711Y276498D01*
X41738Y276484D01*
X41808Y276415D01*
X41835Y276401D01*
X41905Y276373D01*
X41960Y276359D01*
X41988Y276332D01*
X42016Y276318D01*
X42071Y276262D01*
X42099Y276248D01*
X42203Y276145D01*
X42210Y276124D01*
X42238Y276110D01*
X42314Y276047D01*
X42362Y275999D01*
X42439Y275978D01*
X42508Y275950D01*
X42543Y275916D01*
X42570Y275902D01*
X42626Y275846D01*
X42654Y275833D01*
X42709Y275777D01*
X42737Y275763D01*
X42765Y275735D01*
X42834Y275708D01*
X42924Y275673D01*
X42972Y275624D01*
X43000Y275611D01*
X43180Y275430D01*
X43208Y275416D01*
X43278Y275347D01*
X43375Y275306D01*
X43430Y275292D01*
X43527Y275222D01*
X43597Y275194D01*
X43687Y275160D01*
X43770Y275091D01*
X43791Y275070D01*
X43818Y275056D01*
X43895Y274993D01*
X43929Y274959D01*
X43957Y274945D01*
X44054Y274903D01*
X44207Y274820D01*
X44332Y274765D01*
X44456Y274695D01*
X44553Y274654D01*
X44678Y274584D01*
X44734Y274529D01*
X44762Y274515D01*
X44838Y274453D01*
X44886Y274404D01*
X44976Y274369D01*
X45046Y274342D01*
X45150Y274279D01*
X45219Y274251D01*
X46370Y273683D01*
X46578Y273586D01*
X46703Y273572D01*
X46994Y273433D01*
X47202Y273336D01*
X47258Y273322D01*
X47403Y273288D01*
X47715Y273142D01*
X47896Y273059D01*
X48014Y273038D01*
X48069Y273024D01*
X48145Y272990D01*
X48173Y272976D01*
X48270Y272934D01*
X48464Y272892D01*
X48617Y272823D01*
X48755Y272782D01*
X48839Y272768D01*
X48908Y272740D01*
X49061Y272671D01*
X49116Y272657D01*
X49213Y272643D01*
X49282Y272615D01*
X49435Y272546D01*
X49546Y272518D01*
X49650Y272497D01*
X49837Y272421D01*
X49948Y272393D01*
X50107Y272372D01*
X50219Y272345D01*
X50288Y272317D01*
X50406Y272282D01*
X50600Y272255D01*
X50732Y272234D01*
X50842Y272220D01*
X50898Y272206D01*
X50988Y272171D01*
X51078Y272150D01*
X51148Y272137D01*
X51231Y272123D01*
X51342Y272109D01*
X51522Y272081D01*
X51578Y272067D01*
X51668Y272033D01*
X51758Y272012D01*
X51827Y271998D01*
X51980Y271984D01*
X52132Y271956D01*
X52188Y271943D01*
X52257Y271929D01*
X52333Y271908D01*
X52444Y271880D01*
X52583Y271866D01*
X52826Y271845D01*
X52950Y271832D01*
X53131Y271804D01*
X53269Y271776D01*
X53394Y271762D01*
X53699Y271748D01*
X53880Y271735D01*
X54642Y271721D01*
X56965Y271714D01*
X57007Y271728D01*
X57922Y271741D01*
X57964Y271755D01*
X58352Y271769D01*
X58394Y271783D01*
X58484Y271804D01*
X58768Y271838D01*
X58865Y271852D01*
X59045Y271866D01*
X59212Y271880D01*
X59253Y271894D01*
X59309Y271908D01*
X59406Y271936D01*
X59482Y271956D01*
X59552Y271970D01*
X59739Y271991D01*
X59871Y272012D01*
X59926Y272026D01*
X60002Y272047D01*
X60072Y272074D01*
X60169Y272088D01*
X60224Y272102D01*
X60398Y272123D01*
X60481Y272137D01*
X60550Y272150D01*
X60661Y272178D01*
X60779Y272213D01*
X60834Y272227D01*
X61028Y272255D01*
X61188Y272275D01*
X61257Y272289D01*
X61327Y272317D01*
X61486Y272365D01*
X61542Y272379D01*
X61715Y272400D01*
X61770Y272414D01*
X61881Y272456D01*
X61999Y272504D01*
X62193Y272546D01*
X62346Y272615D01*
X62415Y272643D01*
X62512Y272657D01*
X62568Y272671D01*
X62720Y272740D01*
X62790Y272768D01*
X62949Y272802D01*
X63060Y272844D01*
X63136Y272879D01*
X63206Y272906D01*
X63324Y272927D01*
X63379Y272941D01*
X63518Y273010D01*
X63573Y273024D01*
X63650Y273045D01*
X63795Y273080D01*
X63899Y273142D01*
X63989Y273177D01*
X64065Y273211D01*
X64274Y273309D01*
X64412Y273322D01*
X64537Y273392D01*
X64662Y273447D01*
X64731Y273475D01*
X64939Y273572D01*
X65036Y273586D01*
X65113Y273607D01*
X65258Y273683D01*
X65328Y273711D01*
X66035Y274071D01*
X66132Y274113D01*
X66312Y274210D01*
X66409Y274251D01*
X66562Y274335D01*
X66659Y274376D01*
X66784Y274446D01*
X66853Y274515D01*
X66922Y274557D01*
X66978Y274612D01*
X67075Y274654D01*
X67144Y274681D01*
X67227Y274737D01*
X67325Y274778D01*
X67394Y274806D01*
X67470Y274869D01*
X67491Y274889D01*
X67519Y274903D01*
X67546Y274931D01*
X67574Y274945D01*
X67643Y275014D01*
X67782Y275070D01*
X67810Y275084D01*
X67921Y275153D01*
X68053Y275201D01*
X68163Y275271D01*
X68240Y275306D01*
X68330Y275340D01*
X68351Y275361D01*
X68378Y275375D01*
X68448Y275444D01*
X68475Y275458D01*
X68656Y275638D01*
X68684Y275652D01*
X68711Y275680D01*
X68781Y275708D01*
X68871Y275742D01*
X68947Y275819D01*
X68975Y275833D01*
X69100Y275930D01*
X69127Y275957D01*
X69259Y276006D01*
X69308Y276040D01*
X69363Y276096D01*
X69391Y276110D01*
X69557Y276276D01*
X69585Y276290D01*
X69640Y276346D01*
X69710Y276373D01*
X69800Y276408D01*
X69821Y276429D01*
X69848Y276443D01*
X69918Y276512D01*
X69946Y276526D01*
X70036Y276616D01*
X70050Y276644D01*
X70098Y276678D01*
X70133Y276713D01*
X70147Y276741D01*
X70181Y276775D01*
X70209Y276789D01*
X70251Y276831D01*
X70278Y276845D01*
X70320Y276886D01*
X70472Y276942D01*
X70542Y277011D01*
X70570Y277025D01*
X70646Y277087D01*
X70660Y277115D01*
X70722Y277178D01*
X70750Y277192D01*
X70785Y277226D01*
X70798Y277254D01*
X70861Y277316D01*
X70889Y277330D01*
X70909Y277351D01*
X70923Y277379D01*
X70999Y277455D01*
X71027Y277469D01*
X71069Y277511D01*
X71097Y277524D01*
X71124Y277552D01*
X71256Y277601D01*
X71305Y277635D01*
X71360Y277691D01*
X71388Y277705D01*
X71464Y277781D01*
X71478Y277809D01*
X71547Y277878D01*
X71561Y277906D01*
X71589Y277975D01*
X71603Y278030D01*
X71665Y278107D01*
X71762Y278204D01*
X71831Y278232D01*
X71922Y278266D01*
X71970Y278301D01*
X72026Y278356D01*
X72053Y278370D01*
X72130Y278447D01*
X72144Y278474D01*
X72227Y278557D01*
X72255Y278668D01*
X72296Y278738D01*
X72317Y278759D01*
X72372Y278772D01*
X72449Y278793D01*
X72470Y278814D01*
X72497Y278828D01*
X72553Y278883D01*
X72580Y278897D01*
X72670Y278987D01*
X72684Y279015D01*
X72754Y279084D01*
X72782Y279154D01*
X72816Y279244D01*
X72865Y279334D01*
X72851Y279390D01*
X72788Y279410D01*
X72705Y279396D01*
X72650Y279341D01*
X72622Y279327D01*
X72594Y279299D01*
X72566Y279286D01*
X72532Y279251D01*
X72518Y279223D01*
X72456Y279161D01*
X72428Y279147D01*
X72393Y279112D01*
X72379Y279084D01*
X72303Y279008D01*
X72275Y278994D01*
X72255Y278974D01*
X72241Y278946D01*
X72053Y278759D01*
X72033Y278752D01*
X72019Y278724D01*
X71929Y278634D01*
X71901Y278620D01*
X71866Y278585D01*
X71852Y278557D01*
X71776Y278481D01*
X71748Y278467D01*
X71727Y278447D01*
X71714Y278419D01*
X71402Y278107D01*
X71374Y278093D01*
X71339Y278058D01*
X71325Y278030D01*
X71263Y277968D01*
X71235Y277954D01*
X71200Y277920D01*
X71187Y277892D01*
X71124Y277829D01*
X71097Y277816D01*
X71069Y277788D01*
X71041Y277774D01*
X70986Y277719D01*
X70889Y277691D01*
X70819Y277649D01*
X70750Y277580D01*
X70722Y277566D01*
X70674Y277531D01*
X70660Y277504D01*
X70105Y276949D01*
X70098Y276928D01*
X70070Y276914D01*
X70029Y276873D01*
X70001Y276859D01*
X69946Y276803D01*
X69918Y276789D01*
X69848Y276762D01*
X69793Y276748D01*
X69751Y276706D01*
X69731Y276699D01*
X69724Y276678D01*
X69696Y276665D01*
X69668Y276637D01*
X69640Y276623D01*
X69578Y276560D01*
X69564Y276533D01*
X69530Y276498D01*
X69502Y276484D01*
X69446Y276429D01*
X69419Y276415D01*
X69391Y276387D01*
X69335Y276373D01*
X69245Y276339D01*
X69169Y276262D01*
X69141Y276248D01*
X69065Y276186D01*
X69030Y276151D01*
X69002Y276138D01*
X68905Y276096D01*
X68808Y276040D01*
X68739Y275971D01*
X68711Y275957D01*
X68531Y275777D01*
X68503Y275763D01*
X68475Y275735D01*
X68406Y275708D01*
X68316Y275673D01*
X68240Y275597D01*
X68212Y275583D01*
X68136Y275520D01*
X68115Y275500D01*
X68087Y275486D01*
X68060Y275458D01*
X67928Y275410D01*
X67879Y275375D01*
X67838Y275333D01*
X67810Y275319D01*
X67782Y275292D01*
X67754Y275278D01*
X67685Y275208D01*
X67657Y275194D01*
X67560Y275153D01*
X67297Y275028D01*
X67200Y274973D01*
X66770Y274765D01*
X66700Y274723D01*
X66645Y274668D01*
X66617Y274654D01*
X66589Y274626D01*
X66562Y274612D01*
X66520Y274571D01*
X66492Y274557D01*
X66465Y274529D01*
X66375Y274494D01*
X66305Y274466D01*
X66215Y274404D01*
X66146Y274376D01*
X66056Y274342D01*
X65972Y274286D01*
X65896Y274251D01*
X65806Y274217D01*
X65695Y274147D01*
X65619Y274113D01*
X65549Y274085D01*
X65425Y274016D01*
X65300Y273960D01*
X65064Y273849D01*
X64932Y273829D01*
X64863Y273801D01*
X64502Y273620D01*
X64329Y273544D01*
X64121Y273447D01*
X63996Y273433D01*
X63816Y273350D01*
X63747Y273322D01*
X63650Y273309D01*
X63476Y273246D01*
X63330Y273184D01*
X63233Y273170D01*
X63178Y273156D01*
X62984Y273073D01*
X62915Y273045D01*
X62783Y273024D01*
X62713Y272997D01*
X62540Y272920D01*
X62325Y272872D01*
X62263Y272837D01*
X62193Y272809D01*
X62096Y272782D01*
X62041Y272768D01*
X61965Y272747D01*
X61895Y272719D01*
X61819Y272698D01*
X61812Y272691D01*
X61736Y272671D01*
X61680Y272657D01*
X61500Y272643D01*
X61445Y272629D01*
X61313Y272608D01*
X61257Y272594D01*
X61188Y272567D01*
X61070Y272532D01*
X61015Y272518D01*
X60918Y272504D01*
X60786Y272483D01*
X60633Y272428D01*
X60557Y272407D01*
X60446Y272379D01*
X60245Y272345D01*
X60189Y272331D01*
X60120Y272303D01*
X60065Y272289D01*
X59981Y272275D01*
X59871Y272262D01*
X59787Y272248D01*
X59662Y272234D01*
X59385Y272192D01*
X59309Y272171D01*
X59212Y272157D01*
X59156Y272144D01*
X58907Y272130D01*
X58865Y272116D01*
X58401Y272095D01*
X58262Y272081D01*
X58137Y272067D01*
X58054Y272054D01*
X57984Y272040D01*
X57874Y272026D01*
X57707Y272012D01*
X57485Y271998D01*
X57000Y271984D01*
X56882Y271977D01*
X56840Y271991D01*
X56494Y271977D01*
X54712Y271984D01*
X54663Y271977D01*
X54622Y271991D01*
X54580Y271977D01*
X54358Y271991D01*
X53970Y272005D01*
X53928Y272019D01*
X53651Y272033D01*
X53609Y272047D01*
X53512Y272060D01*
X53457Y272074D01*
X53235Y272088D01*
X53006Y272109D01*
X52729Y272123D01*
X52618Y272137D01*
X52437Y272150D01*
X52285Y272178D01*
X52208Y272199D01*
X51876Y272241D01*
X51585Y272282D01*
X51529Y272296D01*
X51432Y272324D01*
X51321Y272352D01*
X51189Y272372D01*
X51002Y272393D01*
X50856Y272428D01*
X50780Y272463D01*
X50641Y272504D01*
X50551Y272525D01*
X50496Y272539D01*
X50420Y272574D01*
X50350Y272601D01*
X50184Y272629D01*
X50045Y272643D01*
X49948Y272657D01*
X49858Y272677D01*
X49705Y272733D01*
X49587Y272768D01*
X49497Y272789D01*
X49442Y272802D01*
X49366Y272837D01*
X49241Y272892D01*
X49109Y272913D01*
X48998Y272955D01*
X48853Y273017D01*
X48797Y273031D01*
X48651Y273066D01*
X48499Y273135D01*
X48381Y273170D01*
X48277Y273191D01*
X48208Y273218D01*
X48062Y273281D01*
X47951Y273309D01*
X47868Y273322D01*
X47549Y273475D01*
X47369Y273558D01*
X47272Y273572D01*
X47216Y273586D01*
X46953Y273711D01*
X46883Y273738D01*
X46703Y273822D01*
X46648Y273836D01*
X46543Y273856D01*
X46474Y273884D01*
X46370Y273946D01*
X46280Y273981D01*
X46211Y274009D01*
X46127Y274064D01*
X46058Y274092D01*
X45906Y274161D01*
X45885Y274182D01*
X45857Y274196D01*
X45732Y274251D01*
X45607Y274321D01*
X45483Y274376D01*
X45330Y274459D01*
X45205Y274515D01*
X45136Y274557D01*
X45060Y274619D01*
X44997Y274668D01*
X44970Y274681D01*
X44900Y274751D01*
X44824Y274772D01*
X44741Y274813D01*
X44637Y274876D01*
X44567Y274903D01*
X44248Y275056D01*
X44221Y275070D01*
X44193Y275098D01*
X44165Y275111D01*
X44110Y275167D01*
X44082Y275181D01*
X44006Y275243D01*
X43971Y275278D01*
X43902Y275306D01*
X43846Y275319D01*
X43770Y275382D01*
X43735Y275416D01*
X43707Y275430D01*
X43631Y275493D01*
X43597Y275527D01*
X43569Y275541D01*
X43430Y275597D01*
X43402Y275611D01*
X43305Y275680D01*
X43250Y275694D01*
X43125Y275763D01*
X43049Y275826D01*
X43000Y275860D01*
X42945Y275916D01*
X42917Y275930D01*
X42792Y275985D01*
X42765Y275999D01*
X42688Y276061D01*
X42640Y276096D01*
X42473Y276262D01*
X42446Y276276D01*
X42376Y276346D01*
X42279Y276373D01*
X42182Y276429D01*
X42127Y276484D01*
X42099Y276498D01*
X42023Y276574D01*
X42009Y276602D01*
X41988Y276623D01*
X41960Y276637D01*
X41932Y276665D01*
X41905Y276678D01*
X41835Y276748D01*
X41738Y276775D01*
X41669Y276817D01*
X41627Y276859D01*
X41600Y276873D01*
X41572Y276900D01*
X41544Y276914D01*
X41523Y276935D01*
X41509Y276963D01*
X41281Y277192D01*
X41260Y277199D01*
X41246Y277226D01*
X40892Y277580D01*
X40865Y277594D01*
X40795Y277663D01*
X40767Y277677D01*
X40726Y277691D01*
X40636Y277725D01*
X40553Y277795D01*
X40504Y277829D01*
X39069Y279265D01*
X39055Y279293D01*
X38999Y279348D01*
X38972Y279417D01*
X38951Y279494D01*
X38930Y279514D01*
X38916Y279542D01*
X38847Y279611D01*
X38833Y279639D01*
X38479Y279993D01*
X38458Y280000D01*
X38445Y280028D01*
X38257Y280215D01*
X38230Y280229D01*
X38167Y280291D01*
X38153Y280319D01*
X38126Y280347D01*
X38112Y280374D01*
X38070Y280416D01*
X38056Y280443D01*
X38029Y280513D01*
X38015Y280568D01*
X37931Y280652D01*
X37918Y280679D01*
X37855Y280756D01*
X37827Y280769D01*
X37751Y280846D01*
X37737Y280873D01*
X37682Y280929D01*
X37668Y280957D01*
X37640Y281026D01*
X37606Y281116D01*
X37529Y281192D01*
X37515Y281220D01*
X37335Y281400D01*
X37321Y281428D01*
X37280Y281470D01*
X37266Y281497D01*
X37238Y281567D01*
X37183Y281664D01*
X37141Y281705D01*
X37127Y281733D01*
X37099Y281761D01*
X37086Y281789D01*
X37016Y281858D01*
X37002Y281886D01*
X36975Y281955D01*
X36940Y282045D01*
X36905Y282094D01*
X36850Y282177D01*
X36829Y282253D01*
X36808Y282302D01*
X36746Y282378D01*
X36711Y282413D01*
X36697Y282440D01*
X36670Y282468D01*
X36656Y282496D01*
X36600Y282551D01*
X36572Y282621D01*
X36559Y282676D01*
X36496Y282752D01*
X36462Y282787D01*
X36448Y282815D01*
X36385Y282891D01*
X36365Y282912D01*
X36351Y282940D01*
X36323Y282967D01*
X36309Y283023D01*
X36073Y283481D01*
X36032Y283578D01*
X35976Y283675D01*
X35921Y283730D01*
X35907Y283758D01*
X35844Y283834D01*
X35824Y283855D01*
X35810Y283883D01*
X35754Y284008D01*
X35699Y284105D01*
X35629Y284257D01*
X35560Y284382D01*
X35491Y284535D01*
X35435Y284632D01*
X35352Y284812D01*
X35338Y284840D01*
X35269Y284951D01*
X35241Y285020D01*
X35206Y285110D01*
X35130Y285256D01*
X35116Y285311D01*
X35082Y285471D01*
X35005Y285616D01*
X34978Y285686D01*
X34853Y285949D01*
X34839Y286046D01*
X34825Y286102D01*
X34790Y286192D01*
X34770Y286213D01*
X34728Y286310D01*
X34700Y286379D01*
X34589Y286615D01*
X34576Y286670D01*
X34555Y286774D01*
X34527Y286843D01*
X34451Y287031D01*
X34437Y287128D01*
X34388Y287260D01*
X34354Y287336D01*
X34326Y287405D01*
X34312Y287461D01*
X34277Y287606D01*
X34250Y287676D01*
X34215Y287752D01*
X34187Y287821D01*
X34173Y287877D01*
X34160Y287974D01*
X34090Y288126D01*
X34062Y288196D01*
X34049Y288251D01*
X34014Y288397D01*
X33986Y288466D01*
X33965Y288528D01*
X33938Y288626D01*
X33924Y288681D01*
X33910Y288861D01*
X33896Y288917D01*
X33875Y289049D01*
X33861Y289104D01*
X33834Y289173D01*
X33785Y289333D01*
X33771Y289471D01*
X33757Y289527D01*
X33743Y289610D01*
X33702Y289707D01*
X33660Y289874D01*
X33646Y289971D01*
X33633Y290151D01*
X33619Y290207D01*
X33598Y290283D01*
X33563Y290401D01*
X33521Y290567D01*
X33487Y290851D01*
X33431Y291073D01*
X33411Y291261D01*
X33390Y291475D01*
X33376Y291739D01*
X33362Y291864D01*
X33348Y292113D01*
X33334Y292224D01*
X33321Y292307D01*
X33307Y292363D01*
X33293Y292474D01*
X33279Y292710D01*
X33265Y292890D01*
X33251Y293140D01*
X33237Y293583D01*
X33217Y293632D01*
X33196Y293653D01*
X33140Y293666D01*
D02*
G37*
%LPD*%
G36*
X82801Y291004D02*
X82898Y290948D01*
X83023Y290893D01*
X83099Y290872D01*
X83148Y290837D01*
X83168Y290775D01*
X83162Y284639D01*
X83168Y284493D01*
X83155Y284451D01*
X83141Y284396D01*
X83134Y284139D01*
X83141Y284091D01*
X83113Y284008D01*
X82981Y283876D01*
X82884Y283862D01*
X82537Y283848D01*
X82496Y283834D01*
X82427Y283820D01*
X82385Y283834D01*
X82274Y283848D01*
X82232Y283834D01*
X82135Y283820D01*
X82094Y283834D01*
X81851Y283827D01*
X81678Y283834D01*
X81636Y283820D01*
X81428Y283834D01*
X81386Y283820D01*
X78446Y283834D01*
X78384Y283897D01*
X78377Y284042D01*
X78384Y284105D01*
X78370Y284118D01*
X78384Y284160D01*
Y284216D01*
Y284230D01*
X78377Y289146D01*
X78391Y290116D01*
X78398Y290165D01*
X78384Y290207D01*
X78405Y290602D01*
X78419Y290782D01*
X78440Y290831D01*
X78509Y290928D01*
X78523Y290955D01*
X78558Y290990D01*
X78654Y291004D01*
X78745Y290983D01*
X78863Y290935D01*
X79188Y290914D01*
X79459Y290893D01*
X79500Y290879D01*
X79681Y290893D01*
X79847Y290879D01*
X79889Y290893D01*
X80138Y290879D01*
X80180Y290893D01*
X80402Y290879D01*
X81865Y290900D01*
X82267Y290928D01*
X82447Y290942D01*
X82503Y290955D01*
X82621Y291004D01*
X82676Y291018D01*
X82801Y291004D01*
D02*
G37*
G36*
X69211Y291143D02*
X69412Y291150D01*
X69481Y291136D01*
X69543Y291129D01*
X69585Y291143D01*
X69675Y291150D01*
X69744Y291136D01*
X69800Y291122D01*
X70160Y291108D01*
X70230Y291080D01*
X70313Y290997D01*
X70327Y290969D01*
X70355Y290900D01*
X70375Y290532D01*
X70389Y290463D01*
X70396Y290387D01*
X70382Y290345D01*
X70389Y290103D01*
X70382Y289929D01*
X70396Y289888D01*
X70382Y289707D01*
X70396Y289569D01*
X70389Y288757D01*
X70396Y288653D01*
X70382Y288612D01*
X70389Y288397D01*
X70382Y288196D01*
X70396Y288154D01*
X70375Y288036D01*
X70361Y287814D01*
X70348Y287648D01*
X70327Y287599D01*
X70265Y287523D01*
X70237Y287495D01*
X70209Y287481D01*
X70167Y287468D01*
X70070Y287454D01*
X70043Y287468D01*
X70001Y287454D01*
X69751Y287440D01*
X69710Y287426D01*
X69481Y287433D01*
X66382Y287426D01*
X66340Y287440D01*
X66298D01*
X66291Y287433D01*
X66118Y287426D01*
X66049Y287454D01*
X65792Y287461D01*
X65716Y287454D01*
X65674Y287468D01*
X65647Y287481D01*
X65570Y287544D01*
X65529Y287586D01*
X65501Y287655D01*
X65487Y288043D01*
X65473Y288085D01*
X65459Y288182D01*
X65473Y288223D01*
X65487Y288307D01*
X65473Y288348D01*
X65459Y288445D01*
X65473Y288501D01*
X65466Y288743D01*
X65473Y288903D01*
X65459Y288944D01*
X65466Y289132D01*
X65459Y290886D01*
X65487Y290969D01*
X65522Y291004D01*
X65577Y291018D01*
X65653Y291039D01*
X65723Y291066D01*
X65799Y291101D01*
X65938Y291115D01*
X66527Y291136D01*
X67359Y291150D01*
X68614Y291157D01*
X68656Y291143D01*
X68885Y291150D01*
X69072Y291143D01*
X69113Y291157D01*
X69211Y291143D01*
D02*
G37*
D18*
X145500Y88750D02*
D03*
Y56750D02*
D03*
D39*
X331693Y84089D02*
D03*
D40*
X230693Y58689D02*
D03*
Y84089D02*
D03*
Y109489D02*
D03*
D41*
X308750Y489250D02*
D03*
X316750D02*
D03*
X343250Y488750D02*
D03*
X335250D02*
D03*
X112250Y463508D02*
D03*
X104250D02*
D03*
X123750D02*
D03*
X131750D02*
D03*
D42*
X301250Y464000D02*
D03*
Y438600D02*
D03*
X358750Y464000D02*
D03*
Y438600D02*
D03*
D43*
X342700Y470050D02*
D03*
X330000D02*
D03*
X317300D02*
D03*
X342700Y432550D02*
D03*
X330000D02*
D03*
X317300D02*
D03*
D44*
X273500Y274811D02*
D03*
Y226811D02*
D03*
X258500Y226811D02*
D03*
X243500Y226811D02*
D03*
X228500D02*
D03*
X258500Y274811D02*
D03*
X243500Y274811D02*
D03*
X213500D02*
D03*
X228500Y274811D02*
D03*
D45*
X213500Y229311D02*
D03*
D46*
X34250Y104750D02*
D03*
Y133750D02*
D03*
D47*
X457000Y412076D02*
D03*
Y421676D02*
D03*
D48*
X466849Y435727D02*
D03*
X473649D02*
D03*
D49*
X167947Y257371D02*
D03*
Y333571D02*
D03*
X167947Y384471D02*
D03*
X401947D02*
D03*
Y206471D02*
D03*
X401947Y295471D02*
D03*
X167947Y206471D02*
D03*
D50*
X315250Y259250D02*
D03*
X315250Y319250D02*
D03*
X355250D02*
D03*
X355250Y259250D02*
D03*
X282750Y379249D02*
D03*
X282750Y319250D02*
D03*
X315250Y319250D02*
D03*
X315250Y379249D02*
D03*
D51*
X72000Y147450D02*
D03*
Y118250D02*
D03*
X109500Y147450D02*
D03*
Y118250D02*
D03*
X144750Y119650D02*
D03*
X144750Y148850D02*
D03*
D52*
X192250Y38250D02*
D03*
Y56250D02*
D03*
D53*
X315000Y218811D02*
D03*
X331000Y218811D02*
D03*
X213500Y309061D02*
D03*
X229500D02*
D03*
D54*
X271250Y448300D02*
D03*
Y464300D02*
D03*
D55*
X285250Y464250D02*
D03*
Y455050D02*
D03*
X168750Y42690D02*
D03*
Y51890D02*
D03*
X431167Y384149D02*
D03*
X431167Y374949D02*
D03*
X346750Y379100D02*
D03*
Y369900D02*
D03*
D56*
X34250Y237000D02*
D03*
X52250D02*
D03*
X34250Y211750D02*
D03*
X52250D02*
D03*
D57*
X213500Y295561D02*
D03*
X222700D02*
D03*
X315226Y232063D02*
D03*
X324426Y232063D02*
D03*
D58*
X213500Y196772D02*
D03*
X223100D02*
D03*
X447400Y435726D02*
D03*
X457000Y435727D02*
D03*
D59*
X293462Y298212D02*
D03*
X300250Y305000D02*
D03*
D60*
X16836Y491645D02*
D03*
X492909Y492701D02*
D03*
X492478Y15188D02*
D03*
D61*
X240792Y457200D02*
D03*
Y464000D02*
D03*
D62*
X34250Y179000D02*
D03*
D63*
X59650D02*
D03*
D64*
X192000Y484000D02*
D03*
X51000Y457000D02*
D03*
X457000Y51000D02*
D03*
Y457000D02*
D03*
X132000Y484000D02*
D03*
X102000D02*
D03*
X72000D02*
D03*
X457000Y254000D02*
D03*
X51000Y51000D02*
D03*
X162000Y484000D02*
D03*
D65*
X465000Y138000D02*
D03*
Y349000D02*
D03*
D66*
X95000Y71000D02*
D03*
X406000Y41000D02*
D03*
X413000Y452000D02*
D03*
X95000Y437000D02*
D03*
D67*
X315000Y203311D02*
D03*
X241500Y478750D02*
D03*
X220968Y339000D02*
D03*
X349911Y39320D02*
D03*
X350161Y52070D02*
D03*
X350607Y63513D02*
D03*
X350161Y75070D02*
D03*
X360411Y74570D02*
D03*
X360857Y63014D02*
D03*
X360411Y51570D02*
D03*
X360161Y38820D02*
D03*
X350911Y90320D02*
D03*
X351161Y103070D02*
D03*
X351607Y114514D02*
D03*
X351161Y126070D02*
D03*
X361411Y125570D02*
D03*
X361857Y114014D02*
D03*
X361411Y102570D02*
D03*
X361161Y89820D02*
D03*
X308000Y46100D02*
D03*
X320750Y45850D02*
D03*
X332193Y45405D02*
D03*
X343750Y45850D02*
D03*
X343250Y35600D02*
D03*
X331693Y35155D02*
D03*
X320250Y35600D02*
D03*
X307500Y35850D02*
D03*
Y84500D02*
D03*
X320250Y84250D02*
D03*
X331693Y83804D02*
D03*
X343250Y84250D02*
D03*
X342750Y74000D02*
D03*
X331194Y73554D02*
D03*
X319750Y74000D02*
D03*
X307000Y74250D02*
D03*
X306320Y53339D02*
D03*
X319070Y53089D02*
D03*
X330513Y52643D02*
D03*
X342070Y53089D02*
D03*
X342570Y63339D02*
D03*
X331013Y62893D02*
D03*
X319570Y63339D02*
D03*
X306820Y63589D02*
D03*
Y105339D02*
D03*
X319570Y105089D02*
D03*
X331013Y104643D02*
D03*
X342570Y105089D02*
D03*
X342070Y94839D02*
D03*
X330513Y94393D02*
D03*
X319070Y94839D02*
D03*
X306320Y95089D02*
D03*
X307000Y116000D02*
D03*
X319750Y115750D02*
D03*
X331194Y115304D02*
D03*
X342750Y115750D02*
D03*
X343250Y126000D02*
D03*
X331693Y125554D02*
D03*
X320250Y126000D02*
D03*
X307500Y126250D02*
D03*
X192905Y69250D02*
D03*
X183138Y69052D02*
D03*
X173250Y65020D02*
D03*
X161750Y64750D02*
D03*
X149500Y63250D02*
D03*
X234398Y422690D02*
D03*
X223373Y415288D02*
D03*
X298715Y489190D02*
D03*
X351500Y488750D02*
D03*
M02*
